FILE_TYPE = MACRO_DRAWING;
SET COLOR_WIRE YELLOW;
SET COLOR_PROP MONO;
SET COLOR_DOT WHITE;
SET COLOR_ARC YELLOW;
SET COLOR_BODY GREEN;
SET COLOR_NOTE MONO;
SET PROP_DISPLAY VALUE;
SET PAGE_NUMBER P121;
FORCEADD OFFPAGE..1
(-6600 3350);
FORCEPROP 2 LAST $XR0 101 
J 0
(-6852 3350);
DISPLAY 0.638298 (-6852 3350);
PAINT MONO (-6852 3350);
FORCEPROP 2 LAST $XR1 121 
J 0
(-6972 3350);
DISPLAY 0.638298 (-6972 3350);
PAINT MONO (-6972 3350);
FORCEPROP 2 LAST CDS_LIB mstr_standard
J 0
(-6600 3350);
PAINT ORANGE (-6600 3350);
DISPLAY INVISIBLE (-6600 3350);
FORCEPROP 1 LAST OFFPAGE TRUE
J 0
(-6275 3225);
PAINT GREEN (-6275 3225);
DISPLAY INVISIBLE (-6275 3225);
FORCEPROP 1 LAST COMMENT_BODY TRUE
J 0
(-6475 3250);
DISPLAY 1.404255 (-6475 3250);
PAINT PEACH (-6475 3250);
DISPLAY INVISIBLE (-6475 3250);
FORCEPROP 2 LAST PATH I10
J 0
(-6550 3425);
DISPLAY 1.021277 (-6550 3425);
PAINT ORANGE (-6550 3425);
DISPLAY INVISIBLE (-6550 3425);
FORCEADD OFFPAGE..5
(-6050 1175);
FORCEPROP 2 LAST $XR0 125 
J 0
(-6335 1175);
DISPLAY 0.638298 (-6335 1175);
PAINT MONO (-6335 1175);
FORCEPROP 2 LAST $XR1 139 
J 0
(-6455 1175);
DISPLAY 0.638298 (-6455 1175);
PAINT MONO (-6455 1175);
FORCEPROP 2 LAST PATH I100
J 0
(-6325 1225);
DISPLAY 1.021277 (-6325 1225);
PAINT ORANGE (-6325 1225);
DISPLAY INVISIBLE (-6325 1225);
FORCEPROP 2 LAST CDS_LIB mstr_standard
J 0
(-6050 1175);
PAINT ORANGE (-6050 1175);
DISPLAY INVISIBLE (-6050 1175);
FORCEPROP 1 LAST OFFPAGE TRUE
J 0
(-5725 1050);
DISPLAY 0.872340 (-5725 1050);
PAINT GREEN (-5725 1050);
DISPLAY INVISIBLE (-5725 1050);
FORCEPROP 1 LAST COMMENT_BODY TRUE
J 0
(-5950 1100);
DISPLAY 0.872340 (-5950 1100);
PAINT GREEN (-5950 1100);
DISPLAY INVISIBLE (-5950 1100);
FORCEADD RES..1
(-5100 1175);
FORCEPROP 1 LAST LOCATION R8D11
J 0
(-5150 1225);
DISPLAY 0.617021 (-5150 1225);
PAINT AQUA (-5150 1225);
FORCEPROP 1 LAST VALUE 33.2
J 2
(-5200 1175);
DISPLAY 0.617021 (-5200 1175);
PAINT SKYBLUE (-5200 1175);
FORCEPROP 1 LAST TOLERANCE 1%
J 0
(-5125 1125);
DISPLAY 0.617021 (-5125 1125);
PAINT SKYBLUE (-5125 1125);
FORCEPROP 1 LAST PACK_TYPE 0402
J 0
(-4900 1125);
DISPLAY 0.617021 (-4900 1125);
PAINT SKYBLUE (-4900 1125);
FORCEPROP 1 LASTPIN (-5000 1175) $PN 2
J 0
(-5038 1187);
DISPLAY 0.617021 (-5038 1187);
PAINT ORANGE (-5038 1187);
FORCEPROP 1 LASTPIN (-5200 1175) $PN 1
J 0
(-5188 1187);
DISPLAY 0.617021 (-5188 1187);
PAINT ORANGE (-5188 1187);
FORCEPROP 1 LAST MATERIAL CHIP
J 0
(-5025 1125);
DISPLAY 0.617021 (-5025 1125);
PAINT SKYBLUE (-5025 1125);
FORCEPROP 1 LAST PART_NUMBER G21796-074
J 0
(-5350 1125);
DISPLAY 0.617021 (-5350 1125);
PAINT BLUE (-5350 1125);
FORCEPROP 1 LAST WATTAGE 1/16W
J 2
(-5125 1025);
DISPLAY 0.617021 (-5125 1025);
PAINT SKYBLUE (-5125 1025);
DISPLAY INVISIBLE (-5125 1025);
FORCEPROP 0 LAST ROOM SB
J 0
(-5050 1275);
DISPLAY 1.021277 (-5050 1275);
PAINT ORANGE (-5050 1275);
DISPLAY INVISIBLE (-5050 1275);
FORCEPROP 2 LAST CDS_LIB mstr_discrete
J 0
(-5100 1175);
PAINT ORANGE (-5100 1175);
DISPLAY INVISIBLE (-5100 1175);
FORCEPROP 2 LAST SEC_TYPE 0402
J 0
(-5150 1375);
DISPLAY 1.021277 (-5150 1375);
PAINT ORANGE (-5150 1375);
DISPLAY INVISIBLE (-5150 1375);
FORCEPROP 2 LAST SEC 1
J 0
(-5150 1375);
DISPLAY 0.680851 (-5150 1375);
PAINT MONO (-5150 1375);
DISPLAY INVISIBLE (-5150 1375);
FORCEPROP 2 LAST CDS_LOCATION R8D11
J 0
(-4900 1125);
DISPLAY 0.617021 (-4900 1125);
PAINT AQUA (-4900 1125);
DISPLAY INVISIBLE (-4900 1125);
FORCEPROP 0 LAST CDS_SEC 1
J 0
(-5200 1275);
PAINT ORANGE (-5200 1275);
DISPLAY INVISIBLE (-5200 1275);
FORCEPROP 1 LAST PATH I101
J 0
(-5150 1325);
DISPLAY 0.978723 (-5150 1325);
PAINT WHITE (-5150 1325);
DISPLAY INVISIBLE (-5150 1325);
FORCEADD OFFPAGE..5
(-6600 3700);
FORCEPROP 2 LAST $XR0 121 
J 0
(-6855 3700);
DISPLAY 0.638298 (-6855 3700);
PAINT MONO (-6855 3700);
FORCEPROP 1 LAST COMMENT_BODY TRUE
J 0
(-6500 3625);
DISPLAY 0.872340 (-6500 3625);
PAINT GREEN (-6500 3625);
DISPLAY INVISIBLE (-6500 3625);
FORCEPROP 1 LAST OFFPAGE TRUE
J 0
(-6275 3575);
DISPLAY 0.872340 (-6275 3575);
PAINT GREEN (-6275 3575);
DISPLAY INVISIBLE (-6275 3575);
FORCEPROP 2 LAST PATH I102
J 0
(-6550 3775);
DISPLAY 1.021277 (-6550 3775);
PAINT ORANGE (-6550 3775);
DISPLAY INVISIBLE (-6550 3775);
FORCEPROP 2 LAST CDS_LIB mstr_standard
J 0
(-6600 3700);
PAINT ORANGE (-6600 3700);
DISPLAY INVISIBLE (-6600 3700);
FORCEADD OFFPAGE..5
(-6600 3650);
FORCEPROP 2 LAST $XR0 121 
J 0
(-6855 3650);
DISPLAY 0.638298 (-6855 3650);
PAINT MONO (-6855 3650);
FORCEPROP 1 LAST COMMENT_BODY TRUE
J 0
(-6500 3575);
DISPLAY 0.872340 (-6500 3575);
PAINT GREEN (-6500 3575);
DISPLAY INVISIBLE (-6500 3575);
FORCEPROP 1 LAST OFFPAGE TRUE
J 0
(-6275 3525);
DISPLAY 0.872340 (-6275 3525);
PAINT GREEN (-6275 3525);
DISPLAY INVISIBLE (-6275 3525);
FORCEPROP 2 LAST PATH I103
J 0
(-6550 3725);
DISPLAY 1.021277 (-6550 3725);
PAINT ORANGE (-6550 3725);
DISPLAY INVISIBLE (-6550 3725);
FORCEPROP 2 LAST CDS_LIB mstr_standard
J 0
(-6600 3650);
PAINT ORANGE (-6600 3650);
DISPLAY INVISIBLE (-6600 3650);
FORCEADD OFFPAGE..5
(-6600 3600);
FORCEPROP 2 LAST $XR0 121 
J 0
(-6855 3600);
DISPLAY 0.638298 (-6855 3600);
PAINT MONO (-6855 3600);
FORCEPROP 1 LAST COMMENT_BODY TRUE
J 0
(-6500 3525);
DISPLAY 0.872340 (-6500 3525);
PAINT GREEN (-6500 3525);
DISPLAY INVISIBLE (-6500 3525);
FORCEPROP 1 LAST OFFPAGE TRUE
J 0
(-6275 3475);
DISPLAY 0.872340 (-6275 3475);
PAINT GREEN (-6275 3475);
DISPLAY INVISIBLE (-6275 3475);
FORCEPROP 2 LAST PATH I104
J 0
(-6550 3675);
DISPLAY 1.021277 (-6550 3675);
PAINT ORANGE (-6550 3675);
DISPLAY INVISIBLE (-6550 3675);
FORCEPROP 2 LAST CDS_LIB mstr_standard
J 0
(-6600 3600);
PAINT ORANGE (-6600 3600);
DISPLAY INVISIBLE (-6600 3600);
FORCEADD OFFPAGE..5
(-6600 3550);
FORCEPROP 2 LAST $XR0 121 
J 0
(-6855 3550);
DISPLAY 0.638298 (-6855 3550);
PAINT MONO (-6855 3550);
FORCEPROP 1 LAST COMMENT_BODY TRUE
J 0
(-6500 3475);
DISPLAY 0.872340 (-6500 3475);
PAINT GREEN (-6500 3475);
DISPLAY INVISIBLE (-6500 3475);
FORCEPROP 1 LAST OFFPAGE TRUE
J 0
(-6275 3425);
DISPLAY 0.872340 (-6275 3425);
PAINT GREEN (-6275 3425);
DISPLAY INVISIBLE (-6275 3425);
FORCEPROP 2 LAST PATH I105
J 0
(-6550 3625);
DISPLAY 1.021277 (-6550 3625);
PAINT ORANGE (-6550 3625);
DISPLAY INVISIBLE (-6550 3625);
FORCEPROP 2 LAST CDS_LIB mstr_standard
J 0
(-6600 3550);
PAINT ORANGE (-6600 3550);
DISPLAY INVISIBLE (-6600 3550);
FORCEADD OFFPAGE..5
(-6600 3800);
FORCEPROP 2 LAST $XR0 121 
J 0
(-6855 3800);
DISPLAY 0.638298 (-6855 3800);
PAINT MONO (-6855 3800);
FORCEPROP 1 LAST COMMENT_BODY TRUE
J 0
(-6500 3725);
DISPLAY 0.872340 (-6500 3725);
PAINT GREEN (-6500 3725);
DISPLAY INVISIBLE (-6500 3725);
FORCEPROP 1 LAST OFFPAGE TRUE
J 0
(-6275 3675);
DISPLAY 0.872340 (-6275 3675);
PAINT GREEN (-6275 3675);
DISPLAY INVISIBLE (-6275 3675);
FORCEPROP 2 LAST PATH I106
J 0
(-6550 3875);
DISPLAY 1.021277 (-6550 3875);
PAINT ORANGE (-6550 3875);
DISPLAY INVISIBLE (-6550 3875);
FORCEPROP 2 LAST CDS_LIB mstr_standard
J 0
(-6600 3800);
PAINT ORANGE (-6600 3800);
DISPLAY INVISIBLE (-6600 3800);
FORCEADD OFFPAGE..4
(-4125 1175);
FORCEPROP 2 LAST $XR0 121 
J 0
(-3939 1175);
DISPLAY 0.638298 (-3939 1175);
PAINT MONO (-3939 1175);
FORCEPROP 2 LAST CDS_LIB mstr_standard
J 0
(-4125 1175);
PAINT ORANGE (-4125 1175);
DISPLAY INVISIBLE (-4125 1175);
FORCEPROP 2 LAST PATH I107
J 0
(-3950 1250);
DISPLAY 1.021277 (-3950 1250);
PAINT ORANGE (-3950 1250);
DISPLAY INVISIBLE (-3950 1250);
FORCEPROP 1 LAST OFFPAGE TRUE
J 0
(-3800 1050);
DISPLAY 0.872340 (-3800 1050);
PAINT GREEN (-3800 1050);
DISPLAY INVISIBLE (-3800 1050);
FORCEPROP 1 LAST COMMENT_BODY TRUE
J 0
(-4150 1075);
DISPLAY 0.872340 (-4150 1075);
PAINT GREEN (-4150 1075);
DISPLAY INVISIBLE (-4150 1075);
FORCEADD OFFPAGE..4
(-4125 1025);
FORCEPROP 2 LAST $XR0 121 
J 0
(-3939 1025);
DISPLAY 0.638298 (-3939 1025);
PAINT MONO (-3939 1025);
FORCEPROP 1 LAST COMMENT_BODY TRUE
J 0
(-4150 925);
DISPLAY 0.872340 (-4150 925);
PAINT GREEN (-4150 925);
DISPLAY INVISIBLE (-4150 925);
FORCEPROP 1 LAST OFFPAGE TRUE
J 0
(-3800 900);
DISPLAY 0.872340 (-3800 900);
PAINT GREEN (-3800 900);
DISPLAY INVISIBLE (-3800 900);
FORCEPROP 2 LAST PATH I108
J 0
(-3950 1100);
DISPLAY 1.021277 (-3950 1100);
PAINT ORANGE (-3950 1100);
DISPLAY INVISIBLE (-3950 1100);
FORCEPROP 2 LAST CDS_LIB mstr_standard
J 0
(-4125 1025);
PAINT ORANGE (-4125 1025);
DISPLAY INVISIBLE (-4125 1025);
FORCEADD OFFPAGE..4
(-4125 850);
FORCEPROP 2 LAST $XR0 121 
J 0
(-3939 850);
DISPLAY 0.638298 (-3939 850);
PAINT MONO (-3939 850);
FORCEPROP 1 LAST COMMENT_BODY TRUE
J 0
(-4150 750);
DISPLAY 0.872340 (-4150 750);
PAINT GREEN (-4150 750);
DISPLAY INVISIBLE (-4150 750);
FORCEPROP 1 LAST OFFPAGE TRUE
J 0
(-3800 725);
DISPLAY 0.872340 (-3800 725);
PAINT GREEN (-3800 725);
DISPLAY INVISIBLE (-3800 725);
FORCEPROP 2 LAST PATH I109
J 0
(-3950 925);
DISPLAY 1.021277 (-3950 925);
PAINT ORANGE (-3950 925);
DISPLAY INVISIBLE (-3950 925);
FORCEPROP 2 LAST CDS_LIB mstr_standard
J 0
(-4125 850);
PAINT ORANGE (-4125 850);
DISPLAY INVISIBLE (-4125 850);
FORCEADD OFFPAGE..1
(-6600 3850);
FORCEPROP 2 LAST $XR0 190 
J 0
(-6852 3850);
DISPLAY 0.638298 (-6852 3850);
PAINT MONO (-6852 3850);
FORCEPROP 2 LAST PATH I11
J 0
(-6550 3925);
DISPLAY 1.021277 (-6550 3925);
PAINT ORANGE (-6550 3925);
DISPLAY INVISIBLE (-6550 3925);
FORCEPROP 1 LAST COMMENT_BODY TRUE
J 0
(-6475 3750);
DISPLAY 1.404255 (-6475 3750);
PAINT PEACH (-6475 3750);
DISPLAY INVISIBLE (-6475 3750);
FORCEPROP 1 LAST OFFPAGE TRUE
J 0
(-6275 3725);
PAINT GREEN (-6275 3725);
DISPLAY INVISIBLE (-6275 3725);
FORCEPROP 2 LAST CDS_LIB mstr_standard
J 0
(-6600 3850);
PAINT ORANGE (-6600 3850);
DISPLAY INVISIBLE (-6600 3850);
FORCEADD OFFPAGE..4
(-4125 700);
FORCEPROP 2 LAST $XR0 121 
J 0
(-3939 700);
DISPLAY 0.638298 (-3939 700);
PAINT MONO (-3939 700);
FORCEPROP 1 LAST COMMENT_BODY TRUE
J 0
(-4150 600);
DISPLAY 0.872340 (-4150 600);
PAINT GREEN (-4150 600);
DISPLAY INVISIBLE (-4150 600);
FORCEPROP 1 LAST OFFPAGE TRUE
J 0
(-3800 575);
DISPLAY 0.872340 (-3800 575);
PAINT GREEN (-3800 575);
DISPLAY INVISIBLE (-3800 575);
FORCEPROP 2 LAST PATH I110
J 0
(-3950 775);
DISPLAY 1.021277 (-3950 775);
PAINT ORANGE (-3950 775);
DISPLAY INVISIBLE (-3950 775);
FORCEPROP 2 LAST CDS_LIB mstr_standard
J 0
(-4125 700);
PAINT ORANGE (-4125 700);
DISPLAY INVISIBLE (-4125 700);
FORCEADD OFFPAGE..4
(-4125 550);
FORCEPROP 2 LAST $XR0 121 
J 0
(-3939 550);
DISPLAY 0.638298 (-3939 550);
PAINT MONO (-3939 550);
FORCEPROP 1 LAST COMMENT_BODY TRUE
J 0
(-4150 450);
DISPLAY 0.872340 (-4150 450);
PAINT GREEN (-4150 450);
DISPLAY INVISIBLE (-4150 450);
FORCEPROP 1 LAST OFFPAGE TRUE
J 0
(-3800 425);
DISPLAY 0.872340 (-3800 425);
PAINT GREEN (-3800 425);
DISPLAY INVISIBLE (-3800 425);
FORCEPROP 2 LAST PATH I111
J 0
(-3950 625);
DISPLAY 1.021277 (-3950 625);
PAINT ORANGE (-3950 625);
DISPLAY INVISIBLE (-3950 625);
FORCEPROP 2 LAST CDS_LIB mstr_standard
J 0
(-4125 550);
PAINT ORANGE (-4125 550);
DISPLAY INVISIBLE (-4125 550);
FORCEADD OFFPAGE..1
(-6600 3750);
FORCEPROP 2 LAST $XR0 139 
J 0
(-6852 3750);
DISPLAY 0.638298 (-6852 3750);
PAINT MONO (-6852 3750);
FORCEPROP 2 LAST PATH I21
J 0
(-6550 3825);
DISPLAY 1.021277 (-6550 3825);
PAINT ORANGE (-6550 3825);
DISPLAY INVISIBLE (-6550 3825);
FORCEPROP 1 LAST COMMENT_BODY TRUE
J 0
(-6475 3650);
DISPLAY 1.404255 (-6475 3650);
PAINT PEACH (-6475 3650);
DISPLAY INVISIBLE (-6475 3650);
FORCEPROP 1 LAST OFFPAGE TRUE
J 0
(-6275 3625);
PAINT GREEN (-6275 3625);
DISPLAY INVISIBLE (-6275 3625);
FORCEPROP 2 LAST CDS_LIB mstr_standard
J 0
(-6600 3750);
PAINT ORANGE (-6600 3750);
DISPLAY INVISIBLE (-6600 3750);
FORCEADD OFFPAGE..4
(-1375 2550);
FORCEPROP 2 LAST $XR0 137 
J 0
(-1189 2550);
DISPLAY 0.638298 (-1189 2550);
PAINT MONO (-1189 2550);
FORCEPROP 2 LASTPIN (-1425 2550) SIG_NAME RST_RTCRST_N
J 2
(-1435 2560);
DISPLAY 0.617021 (-1435 2560);
PAINT ORANGE (-1435 2560);
FORCEPROP 2 LAST CDS_LIB mstr_standard
J 0
(-1375 2550);
PAINT ORANGE (-1375 2550);
DISPLAY INVISIBLE (-1375 2550);
FORCEPROP 1 LAST OFFPAGE TRUE
J 0
(-1050 2425);
DISPLAY 0.872340 (-1050 2425);
PAINT GREEN (-1050 2425);
DISPLAY INVISIBLE (-1050 2425);
FORCEPROP 1 LAST COMMENT_BODY TRUE
J 0
(-1400 2450);
DISPLAY 0.872340 (-1400 2450);
PAINT GREEN (-1400 2450);
DISPLAY INVISIBLE (-1400 2450);
FORCEPROP 2 LAST PATH I24
J 0
(-1200 2625);
DISPLAY 1.021277 (-1200 2625);
PAINT ORANGE (-1200 2625);
DISPLAY INVISIBLE (-1200 2625);
FORCEADD OFFPAGE..4
(-1375 2500);
FORCEPROP 2 LAST $XR0 137 
J 0
(-1189 2500);
DISPLAY 0.638298 (-1189 2500);
PAINT MONO (-1189 2500);
FORCEPROP 2 LASTPIN (-1425 2500) SIG_NAME RST_SRTCRST_N
J 2
(-1435 2510);
DISPLAY 0.617021 (-1435 2510);
PAINT ORANGE (-1435 2510);
FORCEPROP 2 LAST CDS_LIB mstr_standard
J 0
(-1375 2500);
PAINT ORANGE (-1375 2500);
DISPLAY INVISIBLE (-1375 2500);
FORCEPROP 1 LAST OFFPAGE TRUE
J 0
(-1050 2375);
DISPLAY 0.872340 (-1050 2375);
PAINT GREEN (-1050 2375);
DISPLAY INVISIBLE (-1050 2375);
FORCEPROP 1 LAST COMMENT_BODY TRUE
J 0
(-1400 2400);
DISPLAY 0.872340 (-1400 2400);
PAINT GREEN (-1400 2400);
DISPLAY INVISIBLE (-1400 2400);
FORCEPROP 2 LAST PATH I25
J 0
(-1200 2575);
DISPLAY 1.021277 (-1200 2575);
PAINT ORANGE (-1200 2575);
DISPLAY INVISIBLE (-1200 2575);
FORCEADD OFFPAGE..2
(-1375 3700);
FORCEPROP 2 LAST $XR0 133 
J 0
(-1186 3700);
DISPLAY 0.638298 (-1186 3700);
PAINT MONO (-1186 3700);
FORCEPROP 2 LAST $XR1 191 
J 0
(-1066 3700);
DISPLAY 0.638298 (-1066 3700);
PAINT MONO (-1066 3700);
FORCEPROP 2 LASTPIN (-1425 3700) SIG_NAME FM_PCH_PRSNT_N
J 2
(-1435 3710);
DISPLAY 0.617021 (-1435 3710);
PAINT ORANGE (-1435 3710);
FORCEPROP 2 LAST CDS_LIB mstr_standard
J 0
(-1375 3700);
PAINT ORANGE (-1375 3700);
DISPLAY INVISIBLE (-1375 3700);
FORCEPROP 1 LAST OFFPAGE TRUE
J 0
(-1050 3575);
DISPLAY 0.872340 (-1050 3575);
PAINT GREEN (-1050 3575);
DISPLAY INVISIBLE (-1050 3575);
FORCEPROP 1 LAST COMMENT_BODY TRUE
J 0
(-1420 3605);
DISPLAY 0.872340 (-1420 3605);
PAINT GREEN (-1420 3605);
DISPLAY INVISIBLE (-1420 3605);
FORCEPROP 2 LAST PATH I27
J 0
(-1200 3775);
DISPLAY 1.021277 (-1200 3775);
PAINT ORANGE (-1200 3775);
DISPLAY INVISIBLE (-1200 3775);
FORCEADD OFFPAGE..2
(-1375 3450);
FORCEPROP 2 LAST $XR0 154 
J 0
(-1186 3450);
DISPLAY 0.638298 (-1186 3450);
PAINT MONO (-1186 3450);
FORCEPROP 2 LAST $XR1 184 
J 0
(-1066 3450);
DISPLAY 0.638298 (-1066 3450);
PAINT MONO (-1066 3450);
FORCEPROP 2 LAST CDS_LIB mstr_standard
J 0
(-1375 3450);
PAINT RED (-1375 3450);
DISPLAY INVISIBLE (-1375 3450);
FORCEPROP 1 LAST OFFPAGE TRUE
J 0
(-1050 3325);
PAINT GREEN (-1050 3325);
DISPLAY INVISIBLE (-1050 3325);
FORCEPROP 1 LAST COMMENT_BODY TRUE
J 0
(-1420 3355);
DISPLAY 1.404255 (-1420 3355);
PAINT GREEN (-1420 3355);
DISPLAY INVISIBLE (-1420 3355);
FORCEPROP 2 LAST PATH I28
J 0
(-1175 3500);
DISPLAY 1.021277 (-1175 3500);
PAINT ORANGE (-1175 3500);
DISPLAY INVISIBLE (-1175 3500);
FORCEADD OFFPAGE..2
(-1375 3150);
FORCEPROP 2 LAST $XR0 111 
J 0
(-1186 3150);
DISPLAY 0.638298 (-1186 3150);
PAINT MONO (-1186 3150);
FORCEPROP 2 LAST $XR1 125 
J 0
(-1066 3150);
DISPLAY 0.638298 (-1066 3150);
PAINT MONO (-1066 3150);
FORCEPROP 2 LAST $XR2 154 
J 0
(-946 3150);
DISPLAY 0.638298 (-946 3150);
PAINT MONO (-946 3150);
FORCEPROP 2 LAST $XR3 184 
J 0
(-826 3150);
DISPLAY 0.638298 (-826 3150);
PAINT MONO (-826 3150);
FORCEPROP 2 LAST CDS_LIB mstr_standard
J 0
(-1375 3150);
PAINT RED (-1375 3150);
DISPLAY INVISIBLE (-1375 3150);
FORCEPROP 1 LAST OFFPAGE TRUE
J 0
(-1050 3025);
PAINT GREEN (-1050 3025);
DISPLAY INVISIBLE (-1050 3025);
FORCEPROP 1 LAST COMMENT_BODY TRUE
J 0
(-1420 3055);
DISPLAY 1.404255 (-1420 3055);
PAINT GREEN (-1420 3055);
DISPLAY INVISIBLE (-1420 3055);
FORCEPROP 2 LAST PATH I29
J 0
(-1175 3200);
DISPLAY 1.021277 (-1175 3200);
PAINT ORANGE (-1175 3200);
DISPLAY INVISIBLE (-1175 3200);
FORCEADD RES..1
(-1925 3150);
FORCEPROP 1 LAST LOCATION R7C15
J 0
(-2125 3150);
DISPLAY 0.617021 (-2125 3150);
PAINT AQUA (-2125 3150);
FORCEPROP 1 LAST PART_NUMBER G21497-005
J 0
(-2375 3100);
DISPLAY 0.617021 (-2375 3100);
PAINT BLUE (-2375 3100);
FORCEPROP 1 LAST VALUE 0.0
J 2
(-1950 3100);
DISPLAY 0.617021 (-1950 3100);
PAINT SKYBLUE (-1950 3100);
FORCEPROP 1 LAST TOLERANCE 5%
J 0
(-1875 3100);
DISPLAY 0.617021 (-1875 3100);
PAINT SKYBLUE (-1875 3100);
FORCEPROP 1 LAST PACK_TYPE 0402
J 0
(-1700 3100);
DISPLAY 0.617021 (-1700 3100);
PAINT SKYBLUE (-1700 3100);
FORCEPROP 1 LAST MATERIAL CHIP
J 0
(-1800 3100);
DISPLAY 0.617021 (-1800 3100);
PAINT SKYBLUE (-1800 3100);
FORCEPROP 1 LAST WATTAGE 1/16W
J 2
(-2050 3100);
DISPLAY 0.617021 (-2050 3100);
PAINT SKYBLUE (-2050 3100);
FORCEPROP 1 LASTPIN (-1825 3150) $PN 2
J 0
(-1863 3162);
DISPLAY 0.617021 (-1863 3162);
PAINT MONO (-1863 3162);
FORCEPROP 1 LASTPIN (-2025 3150) $PN 1
J 0
(-2013 3162);
DISPLAY 0.617021 (-2013 3162);
PAINT MONO (-2013 3162);
FORCEPROP 2 LAST ROOM SB
J 0
(-1975 3290);
DISPLAY 0.787234 (-1975 3290);
PAINT SKYBLUE (-1975 3290);
DISPLAY INVISIBLE (-1975 3290);
FORCEPROP 1 LAST PATH I31
J 0
(-1975 3300);
DISPLAY 0.978723 (-1975 3300);
PAINT WHITE (-1975 3300);
DISPLAY INVISIBLE (-1975 3300);
FORCEPROP 2 LAST CDS_LIB mstr_discrete
J 0
(-1925 3150);
PAINT RED (-1925 3150);
DISPLAY INVISIBLE (-1925 3150);
FORCEPROP 2 LAST CDS_SEC 1
J 0
(-1975 3350);
DISPLAY 1.404255 (-1975 3350);
PAINT ORANGE (-1975 3350);
DISPLAY INVISIBLE (-1975 3350);
FORCEPROP 2 LAST $SEC 1
J 0
(-1975 3350);
DISPLAY 0.936170 (-1975 3350);
PAINT MONO (-1975 3350);
DISPLAY INVISIBLE (-1975 3350);
FORCEPROP 2 LAST CDS_LOCATION R7C15
J 0
(-2125 3150);
DISPLAY 0.617021 (-2125 3150);
PAINT AQUA (-2125 3150);
DISPLAY INVISIBLE (-2125 3150);
FORCEADD OFFPAGE..2
(-1375 3550);
FORCEPROP 2 LAST $XR0 154 
J 0
(-1186 3550);
DISPLAY 0.638298 (-1186 3550);
PAINT MONO (-1186 3550);
FORCEPROP 2 LAST CDS_LIB mstr_standard
J 0
(-1375 3550);
PAINT RED (-1375 3550);
DISPLAY INVISIBLE (-1375 3550);
FORCEPROP 1 LAST OFFPAGE TRUE
J 0
(-1050 3425);
PAINT GREEN (-1050 3425);
DISPLAY INVISIBLE (-1050 3425);
FORCEPROP 1 LAST COMMENT_BODY TRUE
J 0
(-1420 3455);
DISPLAY 1.404255 (-1420 3455);
PAINT GREEN (-1420 3455);
DISPLAY INVISIBLE (-1420 3455);
FORCEPROP 2 LAST PATH I32
J 0
(-1175 3600);
DISPLAY 1.021277 (-1175 3600);
PAINT ORANGE (-1175 3600);
DISPLAY INVISIBLE (-1175 3600);
FORCEADD RES..1
(-1950 3550);
FORCEPROP 1 LAST LOCATION R7C16
J 0
(-2000 3600);
DISPLAY 0.617021 (-2000 3600);
PAINT AQUA (-2000 3600);
FORCEPROP 1 LAST VALUE 33.2
J 2
(-1975 3500);
DISPLAY 0.617021 (-1975 3500);
PAINT SKYBLUE (-1975 3500);
FORCEPROP 1 LAST TOLERANCE 1%
J 0
(-1900 3500);
DISPLAY 0.617021 (-1900 3500);
PAINT SKYBLUE (-1900 3500);
FORCEPROP 1 LAST MATERIAL CHIP
J 0
(-1825 3500);
DISPLAY 0.617021 (-1825 3500);
PAINT SKYBLUE (-1825 3500);
FORCEPROP 1 LAST WATTAGE 1/16W
J 2
(-2075 3500);
DISPLAY 0.617021 (-2075 3500);
PAINT SKYBLUE (-2075 3500);
FORCEPROP 1 LASTPIN (-1850 3550) $PN 2
J 0
(-1888 3562);
DISPLAY 0.617021 (-1888 3562);
PAINT MONO (-1888 3562);
FORCEPROP 1 LASTPIN (-2050 3550) $PN 1
J 0
(-2038 3562);
DISPLAY 0.617021 (-2038 3562);
PAINT MONO (-2038 3562);
FORCEPROP 1 LAST PART_NUMBER G21796-074
J 0
(-2400 3500);
DISPLAY 0.617021 (-2400 3500);
PAINT BLUE (-2400 3500);
FORCEPROP 1 LAST PACK_TYPE 0402
J 0
(-1725 3500);
DISPLAY 0.617021 (-1725 3500);
PAINT SKYBLUE (-1725 3500);
FORCEPROP 2 LAST ROOM SB
J 0
(-2000 3690);
DISPLAY 0.787234 (-2000 3690);
PAINT SKYBLUE (-2000 3690);
DISPLAY INVISIBLE (-2000 3690);
FORCEPROP 1 LAST PATH I33
J 0
(-2000 3700);
DISPLAY 0.978723 (-2000 3700);
PAINT WHITE (-2000 3700);
DISPLAY INVISIBLE (-2000 3700);
FORCEPROP 2 LAST CDS_LIB mstr_discrete
J 0
(-1950 3550);
PAINT RED (-1950 3550);
DISPLAY INVISIBLE (-1950 3550);
FORCEPROP 2 LAST CDS_SEC 1
J 0
(-2000 3750);
DISPLAY 1.404255 (-2000 3750);
PAINT ORANGE (-2000 3750);
DISPLAY INVISIBLE (-2000 3750);
FORCEPROP 2 LAST $SEC 1
J 0
(-2000 3750);
DISPLAY 0.936170 (-2000 3750);
PAINT MONO (-2000 3750);
DISPLAY INVISIBLE (-2000 3750);
FORCEPROP 2 LAST CDS_LOCATION R7C16
J 0
(-2000 3600);
DISPLAY 0.617021 (-2000 3600);
PAINT AQUA (-2000 3600);
DISPLAY INVISIBLE (-2000 3600);
FORCEADD LBG_CORE_QAT_EXT_D..8
(-4050 2800);
FORCEPROP 1 LAST LOCATION U7C1
J 0
(-5350 4200);
DISPLAY 0.617021 (-5350 4200);
PAINT AQUA (-5350 4200);
FORCEPROP 1 LAST PART_NUMBER H91415-002
J 0
(-5350 1400);
DISPLAY 0.617021 (-5350 1400);
PAINT BLUE (-5350 1400);
FORCEPROP 1 LAST MATERIAL IC
J 0
(-5350 4100);
DISPLAY 0.617021 (-5350 4100);
PAINT SKYBLUE (-5350 4100);
FORCEPROP 2 LASTPIN (-5400 2550) $PN Y18
J 2
(-5410 2560);
DISPLAY 0.617021 (-5410 2560);
PAINT ORANGE (-5410 2560);
FORCEPROP 2 LASTPIN (-5400 2600) $PN AA20
J 2
(-5410 2610);
DISPLAY 0.617021 (-5410 2610);
PAINT ORANGE (-5410 2610);
FORCEPROP 2 LASTPIN (-5400 2700) $PN AD9
J 2
(-5410 2710);
DISPLAY 0.617021 (-5410 2710);
PAINT ORANGE (-5410 2710);
FORCEPROP 2 LASTPIN (-5400 2800) $PN AF20
J 2
(-5410 2810);
DISPLAY 0.617021 (-5410 2810);
PAINT ORANGE (-5410 2810);
FORCEPROP 2 LASTPIN (-5400 2850) $PN AD20
J 2
(-5410 2860);
DISPLAY 0.617021 (-5410 2860);
PAINT ORANGE (-5410 2860);
FORCEPROP 2 LASTPIN (-5400 3000) $PN AA13
J 2
(-5410 3010);
DISPLAY 0.617021 (-5410 3010);
PAINT ORANGE (-5410 3010);
FORCEPROP 2 LASTPIN (-2700 3700) $PN C70
J 0
(-2690 3710);
DISPLAY 0.617021 (-2690 3710);
PAINT ORANGE (-2690 3710);
FORCEPROP 2 LASTPIN (-5400 3900) $PN AM4
J 2
(-5410 3910);
DISPLAY 0.617021 (-5410 3910);
PAINT ORANGE (-5410 3910);
FORCEPROP 2 LASTPIN (-5400 3350) $PN AJ1
J 2
(-5410 3360);
DISPLAY 0.617021 (-5410 3360);
PAINT ORANGE (-5410 3360);
FORCEPROP 2 LASTPIN (-5400 3850) $PN AH4
J 2
(-5410 3860);
DISPLAY 0.617021 (-5410 3860);
PAINT ORANGE (-5410 3860);
FORCEPROP 2 LASTPIN (-5400 3750) $PN AJ3
J 2
(-5410 3760);
DISPLAY 0.617021 (-5410 3760);
PAINT ORANGE (-5410 3760);
FORCEPROP 2 LASTPIN (-5400 3100) $PN Y7
J 2
(-5410 3110);
DISPLAY 0.617021 (-5410 3110);
PAINT ORANGE (-5410 3110);
FORCEPROP 2 LASTPIN (-5400 3200) $PN AE7
J 2
(-5410 3210);
DISPLAY 0.617021 (-5410 3210);
PAINT ORANGE (-5410 3210);
FORCEPROP 2 LASTPIN (-5400 3250) $PN AG11
J 2
(-5410 3260);
DISPLAY 0.617021 (-5410 3260);
PAINT ORANGE (-5410 3260);
FORCEPROP 2 LASTPIN (-5400 2400) $PN AE18
J 2
(-5410 2410);
DISPLAY 0.617021 (-5410 2410);
PAINT ORANGE (-5410 2410);
FORCEPROP 2 LASTPIN (-5400 2450) $PN AE15
J 2
(-5410 2460);
DISPLAY 0.617021 (-5410 2460);
PAINT ORANGE (-5410 2460);
FORCEPROP 2 LASTPIN (-5400 2500) $PN AE11
J 2
(-5410 2510);
DISPLAY 0.617021 (-5410 2510);
PAINT ORANGE (-5410 2510);
FORCEPROP 2 LASTPIN (-5400 2750) $PN AD17
J 2
(-5410 2760);
DISPLAY 0.617021 (-5410 2760);
PAINT ORANGE (-5410 2760);
FORCEPROP 2 LASTPIN (-2700 2650) $PN P18
J 0
(-2690 2660);
DISPLAY 0.617021 (-2690 2660);
PAINT ORANGE (-2690 2660);
FORCEPROP 2 LASTPIN (-2700 2700) $PN M18
J 0
(-2690 2710);
DISPLAY 0.617021 (-2690 2710);
PAINT ORANGE (-2690 2710);
FORCEPROP 2 LASTPIN (-2700 2750) $PN K20
J 0
(-2690 2760);
DISPLAY 0.617021 (-2690 2760);
PAINT ORANGE (-2690 2760);
FORCEPROP 2 LASTPIN (-2700 2800) $PN V18
J 0
(-2690 2810);
DISPLAY 0.617021 (-2690 2810);
PAINT ORANGE (-2690 2810);
FORCEPROP 2 LASTPIN (-2700 2850) $PN U24
J 0
(-2690 2860);
DISPLAY 0.617021 (-2690 2860);
PAINT ORANGE (-2690 2860);
FORCEPROP 2 LASTPIN (-2700 2900) $PN H20
J 0
(-2690 2910);
DISPLAY 0.617021 (-2690 2910);
PAINT ORANGE (-2690 2910);
FORCEPROP 2 LASTPIN (-5400 2300) $PN AG18
J 2
(-5410 2310);
DISPLAY 0.617021 (-5410 2310);
PAINT ORANGE (-5410 2310);
FORCEPROP 2 LASTPIN (-2700 3050) $PN V22
J 0
(-2690 3060);
DISPLAY 0.617021 (-2690 3060);
PAINT ORANGE (-2690 3060);
FORCEPROP 2 LASTPIN (-2700 3000) $PN R20
J 0
(-2690 3010);
DISPLAY 0.617021 (-2690 3010);
PAINT ORANGE (-2690 3010);
FORCEPROP 2 LASTPIN (-2700 2950) $PN U20
J 0
(-2690 2960);
DISPLAY 0.617021 (-2690 2960);
PAINT ORANGE (-2690 2960);
FORCEPROP 2 LASTPIN (-2700 3750) $PN BW3
J 0
(-2690 3760);
DISPLAY 0.617021 (-2690 3760);
PAINT ORANGE (-2690 3760);
FORCEPROP 2 LASTPIN (-2700 3900) $PN BG26
J 0
(-2690 3910);
DISPLAY 0.617021 (-2690 3910);
PAINT ORANGE (-2690 3910);
FORCEPROP 2 LASTPIN (-2700 3850) $PN BH24
J 0
(-2690 3860);
DISPLAY 0.617021 (-2690 3860);
PAINT ORANGE (-2690 3860);
FORCEPROP 2 LASTPIN (-5400 2200) $PN P48
J 2
(-5410 2210);
DISPLAY 0.617021 (-5410 2210);
PAINT ORANGE (-5410 2210);
FORCEPROP 2 LASTPIN (-5400 2150) $PN P44
J 2
(-5410 2160);
DISPLAY 0.617021 (-5410 2160);
PAINT ORANGE (-5410 2160);
FORCEPROP 2 LASTPIN (-5400 2100) $PN P40
J 2
(-5410 2110);
DISPLAY 0.617021 (-5410 2110);
PAINT ORANGE (-5410 2110);
FORCEPROP 2 LASTPIN (-5400 2050) $PN AT71
J 2
(-5410 2060);
DISPLAY 0.617021 (-5410 2060);
PAINT ORANGE (-5410 2060);
FORCEPROP 2 LASTPIN (-5400 2000) $PN A11
J 2
(-5410 2010);
DISPLAY 0.617021 (-5410 2010);
PAINT ORANGE (-5410 2010);
FORCEPROP 2 LASTPIN (-5400 1950) $PN D10
J 2
(-5410 1960);
DISPLAY 0.617021 (-5410 1960);
PAINT ORANGE (-5410 1960);
FORCEPROP 2 LASTPIN (-5400 1900) $PN C9
J 2
(-5410 1910);
DISPLAY 0.617021 (-5410 1910);
PAINT ORANGE (-5410 1910);
FORCEPROP 2 LASTPIN (-5400 1850) $PN C11
J 2
(-5410 1860);
DISPLAY 0.617021 (-5410 1860);
PAINT ORANGE (-5410 1860);
FORCEPROP 2 LASTPIN (-5400 1800) $PN B10
J 2
(-5410 1810);
DISPLAY 0.617021 (-5410 1810);
PAINT ORANGE (-5410 1810);
FORCEPROP 2 LASTPIN (-5400 1750) $PN C5
J 2
(-5410 1760);
DISPLAY 0.617021 (-5410 1760);
PAINT ORANGE (-5410 1760);
FORCEPROP 2 LASTPIN (-5400 1700) $PN C6
J 2
(-5410 1710);
DISPLAY 0.617021 (-5410 1710);
PAINT ORANGE (-5410 1710);
FORCEPROP 2 LASTPIN (-5400 1650) $PN E18
J 2
(-5410 1660);
DISPLAY 0.617021 (-5410 1660);
PAINT ORANGE (-5410 1660);
FORCEPROP 2 LASTPIN (-5400 1600) $PN C67
J 2
(-5410 1610);
DISPLAY 0.617021 (-5410 1610);
PAINT ORANGE (-5410 1610);
FORCEPROP 2 LASTPIN (-2700 2200) $PN C68
J 0
(-2690 2210);
DISPLAY 0.617021 (-2690 2210);
PAINT ORANGE (-2690 2210);
FORCEPROP 2 LASTPIN (-2700 2150) $PN C18
J 0
(-2690 2160);
DISPLAY 0.617021 (-2690 2160);
PAINT ORANGE (-2690 2160);
FORCEPROP 2 LASTPIN (-2700 2100) $PN D8
J 0
(-2690 2110);
DISPLAY 0.617021 (-2690 2110);
PAINT ORANGE (-2690 2110);
FORCEPROP 2 LASTPIN (-2700 2050) $PN F66
J 0
(-2690 2060);
DISPLAY 0.617021 (-2690 2060);
PAINT ORANGE (-2690 2060);
FORCEPROP 2 LASTPIN (-2700 2000) $PN F69
J 0
(-2690 2010);
DISPLAY 0.617021 (-2690 2010);
PAINT ORANGE (-2690 2010);
FORCEPROP 2 LASTPIN (-2700 1950) $PN F8
J 0
(-2690 1960);
DISPLAY 0.617021 (-2690 1960);
PAINT ORANGE (-2690 1960);
FORCEPROP 2 LASTPIN (-2700 1900) $PN AT69
J 0
(-2690 1910);
DISPLAY 0.617021 (-2690 1910);
PAINT ORANGE (-2690 1910);
FORCEPROP 2 LASTPIN (-2700 1850) $PN AG15
J 0
(-2690 1860);
DISPLAY 0.617021 (-2690 1860);
PAINT ORANGE (-2690 1860);
FORCEPROP 2 LASTPIN (-2700 1800) $PN P37
J 0
(-2690 1810);
DISPLAY 0.617021 (-2690 1810);
PAINT ORANGE (-2690 1810);
FORCEPROP 2 LASTPIN (-2700 1750) $PN V11
J 0
(-2690 1760);
DISPLAY 0.617021 (-2690 1760);
PAINT ORANGE (-2690 1760);
FORCEPROP 2 LASTPIN (-2700 1700) $PN AA58
J 0
(-2690 1710);
DISPLAY 0.617021 (-2690 1710);
PAINT ORANGE (-2690 1710);
FORCEPROP 2 LASTPIN (-2700 1650) $PN AC56
J 0
(-2690 1660);
DISPLAY 0.617021 (-2690 1660);
PAINT ORANGE (-2690 1660);
FORCEPROP 2 LASTPIN (-2700 1600) $PN AF61
J 0
(-2690 1610);
DISPLAY 0.617021 (-2690 1610);
PAINT ORANGE (-2690 1610);
FORCEPROP 2 LASTPIN (-2700 2550) $PN P11
J 0
(-2690 2560);
DISPLAY 0.617021 (-2690 2560);
PAINT ORANGE (-2690 2560);
FORCEPROP 2 LASTPIN (-2700 3450) $PN K2
J 0
(-2690 3460);
DISPLAY 0.617021 (-2690 3460);
PAINT ORANGE (-2690 3460);
FORCEPROP 2 LASTPIN (-2700 3550) $PN J3
J 0
(-2690 3560);
DISPLAY 0.617021 (-2690 3560);
PAINT ORANGE (-2690 3560);
FORCEPROP 2 LASTPIN (-2700 3600) $PN G7
J 0
(-2690 3610);
DISPLAY 0.617021 (-2690 3610);
PAINT ORANGE (-2690 3610);
FORCEPROP 2 LASTPIN (-2700 3250) $PN F5
J 0
(-2690 3260);
DISPLAY 0.617021 (-2690 3260);
PAINT ORANGE (-2690 3260);
FORCEPROP 2 LASTPIN (-2700 3300) $PN L1
J 0
(-2690 3310);
DISPLAY 0.617021 (-2690 3310);
PAINT ORANGE (-2690 3310);
FORCEPROP 2 LASTPIN (-2700 3200) $PN L3
J 0
(-2690 3210);
DISPLAY 0.617021 (-2690 3210);
PAINT ORANGE (-2690 3210);
FORCEPROP 2 LASTPIN (-2700 3150) $PN H4
J 0
(-2690 3160);
DISPLAY 0.617021 (-2690 3160);
PAINT ORANGE (-2690 3160);
FORCEPROP 2 LASTPIN (-2700 3400) $PN K4
J 0
(-2690 3410);
DISPLAY 0.617021 (-2690 3410);
PAINT ORANGE (-2690 3410);
FORCEPROP 2 LASTPIN (-2700 2500) $PN G18
J 0
(-2690 2510);
DISPLAY 0.617021 (-2690 2510);
PAINT ORANGE (-2690 2510);
FORCEPROP 2 LASTPIN (-5400 3700) $PN AH2
J 2
(-5410 3710);
DISPLAY 0.617021 (-5410 3710);
PAINT ORANGE (-5410 3710);
FORCEPROP 2 LASTPIN (-5400 3800) $PN AK4
J 2
(-5410 3810);
DISPLAY 0.617021 (-5410 3810);
PAINT ORANGE (-5410 3810);
FORCEPROP 2 LASTPIN (-5400 3400) $PN AM2
J 2
(-5410 3410);
DISPLAY 0.617021 (-5410 3410);
PAINT ORANGE (-5410 3410);
FORCEPROP 2 LASTPIN (-5400 3450) $PN AK2
J 2
(-5410 3460);
DISPLAY 0.617021 (-5410 3460);
PAINT ORANGE (-5410 3460);
FORCEPROP 2 LASTPIN (-5400 3500) $PN AL3
J 2
(-5410 3510);
DISPLAY 0.617021 (-5410 3510);
PAINT ORANGE (-5410 3510);
FORCEPROP 2 LASTPIN (-5400 3550) $PN AN3
J 2
(-5410 3560);
DISPLAY 0.617021 (-5410 3560);
PAINT ORANGE (-5410 3560);
FORCEPROP 2 LASTPIN (-5400 3600) $PN AL1
J 2
(-5410 3610);
DISPLAY 0.617021 (-5410 3610);
PAINT ORANGE (-5410 3610);
FORCEPROP 2 LASTPIN (-5400 3050) $PN Y11
J 2
(-5410 3060);
DISPLAY 0.617021 (-5410 3060);
PAINT ORANGE (-5410 3060);
FORCEPROP 2 LASTPIN (-5400 2650) $PN AA17
J 2
(-5410 2660);
DISPLAY 0.617021 (-5410 2660);
PAINT ORANGE (-5410 2660);
FORCEPROP 2 LASTPIN (-5400 3150) $PN AA9
J 2
(-5410 3160);
DISPLAY 0.617021 (-5410 3160);
PAINT ORANGE (-5410 3160);
FORCEPROP 2 LASTPIN (-5400 3650) $PN AN1
J 2
(-5410 3660);
DISPLAY 0.617021 (-5410 3660);
PAINT ORANGE (-5410 3660);
FORCEPROP 2 LASTPIN (-5400 2950) $PN AD13
J 2
(-5410 2960);
DISPLAY 0.617021 (-5410 2960);
PAINT ORANGE (-5410 2960);
FORCEPROP 2 LASTPIN (-5400 2900) $PN Y15
J 2
(-5410 2910);
DISPLAY 0.617021 (-5410 2910);
PAINT ORANGE (-5410 2910);
FORCEPROP 1 LAST PACK_TYPE BGA1
J 0
(-5350 4200);
PAINT SKYBLUE (-5350 4200);
DISPLAY INVISIBLE (-5350 4200);
FORCEPROP 0 LAST ROOM SB
J 0
(-3900 4900);
DISPLAY 1.361702 (-3900 4900);
PAINT ORANGE (-3900 4900);
DISPLAY INVISIBLE (-3900 4900);
FORCEPROP 1 LAST PATH I34
J 0
(-4050 4100);
PAINT GREEN (-4050 4100);
DISPLAY INVISIBLE (-4050 4100);
FORCEPROP 2 LAST CDS_LOCATION U7C1
J 0
(-5350 4200);
DISPLAY 0.617021 (-5350 4200);
PAINT AQUA (-5350 4200);
DISPLAY INVISIBLE (-5350 4200);
FORCEPROP 0 LAST BOM_COST SB
J 0
(-3900 5000);
DISPLAY 1.361702 (-3900 5000);
PAINT ORANGE (-3900 5000);
DISPLAY INVISIBLE (-3900 5000);
FORCEPROP 2 LAST CDS_LIB mstr_u_proc
J 0
(-4050 2800);
PAINT ORANGE (-4050 2800);
DISPLAY INVISIBLE (-4050 2800);
FORCEPROP 2 LAST SEC 8
J 0
(-5350 4250);
DISPLAY 0.680851 (-5350 4250);
PAINT MONO (-5350 4250);
DISPLAY INVISIBLE (-5350 4250);
FORCEPROP 2 LAST SEC_TYPE BGA1
J 0
(-5350 4250);
DISPLAY 1.021277 (-5350 4250);
PAINT ORANGE (-5350 4250);
DISPLAY INVISIBLE (-5350 4250);
FORCEADD RES..2
(-7750 3675);
FORCEPROP 1 LAST VALUE 100.0
J 0
(-7705 3750);
DISPLAY 0.617021 (-7705 3750);
PAINT SKYBLUE (-7705 3750);
FORCEPROP 1 LAST TOLERANCE 1%
J 0
(-7705 3700);
DISPLAY 0.617021 (-7705 3700);
PAINT SKYBLUE (-7705 3700);
FORCEPROP 1 LAST PACK_TYPE 0402
J 0
(-7710 3500);
DISPLAY 0.617021 (-7710 3500);
PAINT SKYBLUE (-7710 3500);
FORCEPROP 1 LASTPIN (-7750 3575) $PN 2
J 0
(-7745 3585);
DISPLAY 0.617021 (-7745 3585);
PAINT ORANGE (-7745 3585);
FORCEPROP 1 LASTPIN (-7750 3775) $PN 1
J 0
(-7745 3737);
DISPLAY 0.617021 (-7745 3737);
PAINT ORANGE (-7745 3737);
FORCEPROP 1 LAST PART_NUMBER G21796-017
J 0
(-7710 3550);
DISPLAY 0.617021 (-7710 3550);
PAINT BLUE (-7710 3550);
FORCEPROP 1 LAST WATTAGE 1/16W
J 0
(-7710 3650);
DISPLAY 0.617021 (-7710 3650);
PAINT SKYBLUE (-7710 3650);
FORCEPROP 1 LAST MATERIAL CHIP
J 0
(-7710 3600);
DISPLAY 0.617021 (-7710 3600);
PAINT SKYBLUE (-7710 3600);
FORCEPROP 1 LAST LOCATION R8C26
J 0
(-7705 3800);
DISPLAY 0.617021 (-7705 3800);
PAINT AQUA (-7705 3800);
FORCEPROP 2 LAST CDS_LOCATION R8C26
J 0
(-7800 3725);
DISPLAY 0.617021 (-7800 3725);
PAINT AQUA (-7800 3725);
DISPLAY INVISIBLE (-7800 3725);
FORCEPROP 0 LAST ROOM SB
J 0
(-7800 3875);
DISPLAY 1.021277 (-7800 3875);
PAINT ORANGE (-7800 3875);
DISPLAY INVISIBLE (-7800 3875);
FORCEPROP 2 LAST SEC_TYPE 0402
J 0
(-7700 3900);
DISPLAY 1.021277 (-7700 3900);
PAINT ORANGE (-7700 3900);
DISPLAY INVISIBLE (-7700 3900);
FORCEPROP 2 LAST SEC 1
J 0
(-7700 3900);
DISPLAY 0.680851 (-7700 3900);
PAINT MONO (-7700 3900);
DISPLAY INVISIBLE (-7700 3900);
FORCEPROP 2 LAST CDS_LIB mstr_discrete
J 0
(-7750 3675);
PAINT ORANGE (-7750 3675);
DISPLAY INVISIBLE (-7750 3675);
FORCEPROP 1 LAST PATH I35
J 0
(-7700 3850);
DISPLAY 0.978723 (-7700 3850);
PAINT WHITE (-7700 3850);
DISPLAY INVISIBLE (-7700 3850);
FORCEADD RES..2
(-8075 2525);
FORCEPROP 1 LAST LOCATION R3N10
J 0
(-8030 2650);
DISPLAY 0.617021 (-8030 2650);
PAINT AQUA (-8030 2650);
FORCEPROP 1 LAST VALUE 10.0K
J 0
(-8030 2600);
DISPLAY 0.617021 (-8030 2600);
PAINT SKYBLUE (-8030 2600);
FORCEPROP 1 LAST TOLERANCE 1%
J 0
(-8030 2550);
DISPLAY 0.617021 (-8030 2550);
PAINT SKYBLUE (-8030 2550);
FORCEPROP 1 LAST MATERIAL CHIP
J 0
(-8035 2450);
DISPLAY 0.617021 (-8035 2450);
PAINT SKYBLUE (-8035 2450);
FORCEPROP 1 LAST WATTAGE 1/16W
J 0
(-8035 2500);
DISPLAY 0.617021 (-8035 2500);
PAINT SKYBLUE (-8035 2500);
FORCEPROP 1 LASTPIN (-8075 2425) $PN 2
J 0
(-8070 2435);
DISPLAY 0.617021 (-8070 2435);
PAINT ORANGE (-8070 2435);
FORCEPROP 1 LASTPIN (-8075 2625) $PN 1
J 0
(-8070 2587);
DISPLAY 0.617021 (-8070 2587);
PAINT ORANGE (-8070 2587);
FORCEPROP 1 LAST PACK_TYPE 0402
J 0
(-8035 2350);
DISPLAY 0.617021 (-8035 2350);
PAINT SKYBLUE (-8035 2350);
FORCEPROP 1 LAST PART_NUMBER G21796-016
J 0
(-8035 2400);
DISPLAY 0.617021 (-8035 2400);
PAINT BLUE (-8035 2400);
FORCEPROP 0 LAST ROOM SB
J 0
(-8025 2750);
DISPLAY 1.021277 (-8025 2750);
PAINT ORANGE (-8025 2750);
DISPLAY INVISIBLE (-8025 2750);
FORCEPROP 1 LAST PATH I37
J 0
(-8025 2700);
DISPLAY 0.978723 (-8025 2700);
PAINT WHITE (-8025 2700);
DISPLAY INVISIBLE (-8025 2700);
FORCEPROP 2 LAST CDS_LIB mstr_discrete
J 0
(-8075 2525);
PAINT ORANGE (-8075 2525);
DISPLAY INVISIBLE (-8075 2525);
FORCEPROP 2 LAST SEC_TYPE 0402
J 0
(-8025 2750);
DISPLAY 1.021277 (-8025 2750);
PAINT ORANGE (-8025 2750);
DISPLAY INVISIBLE (-8025 2750);
FORCEPROP 2 LAST SEC 1
J 0
(-8025 2750);
DISPLAY 0.680851 (-8025 2750);
PAINT MONO (-8025 2750);
DISPLAY INVISIBLE (-8025 2750);
FORCEPROP 2 LAST CDS_LOCATION R3N10
J 0
(-8030 2650);
DISPLAY 0.617021 (-8030 2650);
PAINT AQUA (-8030 2650);
DISPLAY INVISIBLE (-8030 2650);
FORCEADD GND..1
(-7750 3450);
FORCEPROP 3 LASTPIN (-7750 3500) SIG_NAME GND\g
J 0
(-7740 3510);
DISPLAY 0.659574 (-7740 3510);
PAINT MONO (-7740 3510);
DISPLAY INVISIBLE (-7740 3510);
FORCEPROP 1 LAST VOLTAGE 0.0V
J 0
(-7795 3407);
DISPLAY 0.340426 (-7795 3407);
PAINT SKYBLUE (-7795 3407);
DISPLAY INVISIBLE (-7795 3407);
FORCEPROP 1 LAST HDL_POWER GND
J 0
(-7750 3600);
DISPLAY 0.872340 (-7750 3600);
PAINT GREEN (-7750 3600);
DISPLAY INVISIBLE (-7750 3600);
FORCEPROP 1 LAST SIZE 1B
J 0
(-7675 3400);
DISPLAY 0.872340 (-7675 3400);
PAINT AQUA (-7675 3400);
DISPLAY INVISIBLE (-7675 3400);
FORCEPROP 2 LAST CDS_LIB mstr_symbols
J 0
(-7750 3450);
PAINT ORANGE (-7750 3450);
DISPLAY INVISIBLE (-7750 3450);
FORCEPROP 1 LAST BODY_TYPE PLUMBING
J 0
(-7795 3407);
DISPLAY 0.340426 (-7795 3407);
PAINT GREEN (-7795 3407);
DISPLAY INVISIBLE (-7795 3407);
FORCEPROP 1 LAST PATH I39
J 0
(-7675 3450);
DISPLAY 0.872340 (-7675 3450);
PAINT AQUA (-7675 3450);
DISPLAY INVISIBLE (-7675 3450);
FORCEADD P3V3_STBY..1
(-8075 2750);
FORCEPROP 3 LASTPIN (-8075 2700) SIG_NAME P3V3_STBY\g
J 0
(-8065 2710);
DISPLAY 0.659574 (-8065 2710);
PAINT MONO (-8065 2710);
DISPLAY INVISIBLE (-8065 2710);
FORCEPROP 1 LAST VOLTAGE 3.3V
J 0
(-8120 2707);
DISPLAY 0.340426 (-8120 2707);
PAINT SKYBLUE (-8120 2707);
DISPLAY INVISIBLE (-8120 2707);
FORCEPROP 1 LAST HDL_POWER P3V3_STBY
J 0
(-8375 2625);
DISPLAY 0.872340 (-8375 2625);
PAINT ORANGE (-8375 2625);
DISPLAY INVISIBLE (-8375 2625);
FORCEPROP 1 LAST PATH I40
J 0
(-8030 2752);
DISPLAY 0.340426 (-8030 2752);
PAINT GREEN (-8030 2752);
DISPLAY INVISIBLE (-8030 2752);
FORCEPROP 1 LAST BODY_TYPE PLUMBING
J 0
(-8120 2707);
DISPLAY 0.340426 (-8120 2707);
PAINT GREEN (-8120 2707);
DISPLAY INVISIBLE (-8120 2707);
FORCEPROP 1 LAST SIZE 1B
J 0
(-8030 2772);
DISPLAY 0.340426 (-8030 2772);
PAINT GREEN (-8030 2772);
DISPLAY INVISIBLE (-8030 2772);
FORCEPROP 2 LAST CDS_LIB mstr_symbols
J 0
(-8075 2750);
PAINT ORANGE (-8075 2750);
DISPLAY INVISIBLE (-8075 2750);
FORCEADD OFFPAGE..4
(-1375 2850);
FORCEPROP 2 LAST $XR0 125 
J 0
(-1189 2850);
DISPLAY 0.638298 (-1189 2850);
PAINT MONO (-1189 2850);
FORCEPROP 2 LAST $XR1 144 
J 0
(-1069 2850);
DISPLAY 0.638298 (-1069 2850);
PAINT MONO (-1069 2850);
FORCEPROP 2 LAST CDS_LIB mstr_standard
J 0
(-1375 2850);
PAINT MONO (-1375 2850);
DISPLAY INVISIBLE (-1375 2850);
FORCEPROP 1 LAST OFFPAGE TRUE
J 0
(-1050 2725);
DISPLAY 0.872340 (-1050 2725);
PAINT GREEN (-1050 2725);
DISPLAY INVISIBLE (-1050 2725);
FORCEPROP 1 LAST COMMENT_BODY TRUE
J 0
(-1400 2750);
DISPLAY 0.872340 (-1400 2750);
PAINT GREEN (-1400 2750);
DISPLAY INVISIBLE (-1400 2750);
FORCEPROP 2 LAST PATH I41
J 0
(-1325 2925);
DISPLAY 1.021277 (-1325 2925);
PAINT ORANGE (-1325 2925);
DISPLAY INVISIBLE (-1325 2925);
FORCEADD OFFPAGE..2
(-1375 2150);
FORCEPROP 2 LAST $XR0 133 
J 0
(-1186 2150);
DISPLAY 0.638298 (-1186 2150);
PAINT MONO (-1186 2150);
FORCEPROP 2 LAST $XR1 191 
J 0
(-1066 2150);
DISPLAY 0.638298 (-1066 2150);
PAINT MONO (-1066 2150);
FORCEPROP 2 LAST CDS_LIB mstr_standard
J 0
(-1375 2150);
PAINT MONO (-1375 2150);
DISPLAY INVISIBLE (-1375 2150);
FORCEPROP 1 LAST OFFPAGE TRUE
J 0
(-1050 2025);
PAINT GREEN (-1050 2025);
DISPLAY INVISIBLE (-1050 2025);
FORCEPROP 1 LAST COMMENT_BODY TRUE
J 0
(-1420 2055);
DISPLAY 1.404255 (-1420 2055);
PAINT GREEN (-1420 2055);
DISPLAY INVISIBLE (-1420 2055);
FORCEPROP 2 LAST PATH I42
J 0
(-1200 2225);
DISPLAY 1.021277 (-1200 2225);
PAINT ORANGE (-1200 2225);
DISPLAY INVISIBLE (-1200 2225);
FORCEADD OFFPAGE..2
(-1375 2100);
FORCEPROP 2 LAST $XR0 133 
J 0
(-1186 2100);
DISPLAY 0.638298 (-1186 2100);
PAINT MONO (-1186 2100);
FORCEPROP 2 LAST $XR1 191 
J 0
(-1066 2100);
DISPLAY 0.638298 (-1066 2100);
PAINT MONO (-1066 2100);
FORCEPROP 2 LAST CDS_LIB mstr_standard
J 0
(-1375 2100);
PAINT MONO (-1375 2100);
DISPLAY INVISIBLE (-1375 2100);
FORCEPROP 1 LAST OFFPAGE TRUE
J 0
(-1050 1975);
PAINT GREEN (-1050 1975);
DISPLAY INVISIBLE (-1050 1975);
FORCEPROP 1 LAST COMMENT_BODY TRUE
J 0
(-1420 2005);
DISPLAY 1.404255 (-1420 2005);
PAINT GREEN (-1420 2005);
DISPLAY INVISIBLE (-1420 2005);
FORCEPROP 2 LAST PATH I43
J 0
(-1200 2175);
DISPLAY 1.021277 (-1200 2175);
PAINT ORANGE (-1200 2175);
DISPLAY INVISIBLE (-1200 2175);
FORCEADD OFFPAGE..2
(-1375 3400);
FORCEPROP 2 LAST $XR0 184 
J 0
(-1186 3400);
DISPLAY 0.638298 (-1186 3400);
PAINT MONO (-1186 3400);
FORCEPROP 2 LAST CDS_LIB mstr_standard
J 0
(-1375 3400);
PAINT MONO (-1375 3400);
DISPLAY INVISIBLE (-1375 3400);
FORCEPROP 1 LAST OFFPAGE TRUE
J 0
(-1050 3275);
PAINT GREEN (-1050 3275);
DISPLAY INVISIBLE (-1050 3275);
FORCEPROP 1 LAST COMMENT_BODY TRUE
J 0
(-1420 3305);
DISPLAY 1.404255 (-1420 3305);
PAINT GREEN (-1420 3305);
DISPLAY INVISIBLE (-1420 3305);
FORCEPROP 2 LAST PATH I49
J 0
(-1200 3475);
DISPLAY 1.021277 (-1200 3475);
PAINT ORANGE (-1200 3475);
DISPLAY INVISIBLE (-1200 3475);
FORCEADD OFFPAGE..1
(-6600 2650);
FORCEPROP 2 LAST $XR0 109 
J 0
(-6852 2650);
DISPLAY 0.638298 (-6852 2650);
PAINT MONO (-6852 2650);
FORCEPROP 2 LAST $XR1 133 
J 0
(-6972 2650);
DISPLAY 0.638298 (-6972 2650);
PAINT MONO (-6972 2650);
FORCEPROP 2 LAST CDS_LIB mstr_standard
J 0
(-6600 2650);
PAINT MONO (-6600 2650);
DISPLAY INVISIBLE (-6600 2650);
FORCEPROP 1 LAST OFFPAGE TRUE
J 0
(-6275 2525);
DISPLAY 0.872340 (-6275 2525);
PAINT GREEN (-6275 2525);
DISPLAY INVISIBLE (-6275 2525);
FORCEPROP 1 LAST COMMENT_BODY TRUE
J 0
(-6475 2550);
DISPLAY 0.872340 (-6475 2550);
PAINT GREEN (-6475 2550);
DISPLAY INVISIBLE (-6475 2550);
FORCEPROP 2 LAST PATH I50
J 0
(-6550 2725);
DISPLAY 1.021277 (-6550 2725);
PAINT ORANGE (-6550 2725);
DISPLAY INVISIBLE (-6550 2725);
FORCEADD OFFPAGE..1
(-6600 2600);
FORCEPROP 2 LAST $XR0 108 
J 0
(-6852 2600);
DISPLAY 0.638298 (-6852 2600);
PAINT MONO (-6852 2600);
FORCEPROP 2 LAST $XR1 133 
J 0
(-6972 2600);
DISPLAY 0.638298 (-6972 2600);
PAINT MONO (-6972 2600);
FORCEPROP 2 LAST CDS_LIB mstr_standard
J 0
(-6600 2600);
PAINT MONO (-6600 2600);
DISPLAY INVISIBLE (-6600 2600);
FORCEPROP 1 LAST OFFPAGE TRUE
J 0
(-6275 2475);
DISPLAY 0.872340 (-6275 2475);
PAINT GREEN (-6275 2475);
DISPLAY INVISIBLE (-6275 2475);
FORCEPROP 1 LAST COMMENT_BODY TRUE
J 0
(-6475 2500);
DISPLAY 0.872340 (-6475 2500);
PAINT GREEN (-6475 2500);
DISPLAY INVISIBLE (-6475 2500);
FORCEPROP 2 LAST PATH I51
J 0
(-6550 2675);
DISPLAY 1.021277 (-6550 2675);
PAINT ORANGE (-6550 2675);
DISPLAY INVISIBLE (-6550 2675);
FORCEADD OFFPAGE..1
(-6600 2550);
FORCEPROP 2 LAST $XR0 108 
J 0
(-6852 2550);
DISPLAY 0.638298 (-6852 2550);
PAINT MONO (-6852 2550);
FORCEPROP 2 LAST $XR1 133 
J 0
(-6972 2550);
DISPLAY 0.638298 (-6972 2550);
PAINT MONO (-6972 2550);
FORCEPROP 2 LAST CDS_LIB mstr_standard
J 0
(-6600 2550);
PAINT MONO (-6600 2550);
DISPLAY INVISIBLE (-6600 2550);
FORCEPROP 1 LAST OFFPAGE TRUE
J 0
(-6275 2425);
DISPLAY 0.872340 (-6275 2425);
PAINT GREEN (-6275 2425);
DISPLAY INVISIBLE (-6275 2425);
FORCEPROP 1 LAST COMMENT_BODY TRUE
J 0
(-6475 2450);
DISPLAY 0.872340 (-6475 2450);
PAINT GREEN (-6475 2450);
DISPLAY INVISIBLE (-6475 2450);
FORCEPROP 2 LAST PATH I52
J 0
(-6550 2625);
DISPLAY 1.021277 (-6550 2625);
PAINT ORANGE (-6550 2625);
DISPLAY INVISIBLE (-6550 2625);
FORCEADD OFFPAGE..1
(-6600 2500);
FORCEPROP 2 LAST $XR0 108 
J 0
(-6852 2500);
DISPLAY 0.638298 (-6852 2500);
PAINT MONO (-6852 2500);
FORCEPROP 2 LAST $XR1 133 
J 0
(-6972 2500);
DISPLAY 0.638298 (-6972 2500);
PAINT MONO (-6972 2500);
FORCEPROP 2 LAST CDS_LIB mstr_standard
J 0
(-6600 2500);
PAINT MONO (-6600 2500);
DISPLAY INVISIBLE (-6600 2500);
FORCEPROP 1 LAST OFFPAGE TRUE
J 0
(-6275 2375);
DISPLAY 0.872340 (-6275 2375);
PAINT GREEN (-6275 2375);
DISPLAY INVISIBLE (-6275 2375);
FORCEPROP 1 LAST COMMENT_BODY TRUE
J 0
(-6475 2400);
DISPLAY 0.872340 (-6475 2400);
PAINT GREEN (-6475 2400);
DISPLAY INVISIBLE (-6475 2400);
FORCEPROP 2 LAST PATH I53
J 0
(-6550 2575);
DISPLAY 1.021277 (-6550 2575);
PAINT ORANGE (-6550 2575);
DISPLAY INVISIBLE (-6550 2575);
FORCEADD OFFPAGE..1
(-6600 2450);
FORCEPROP 2 LAST $XR0 108 
J 0
(-6852 2450);
DISPLAY 0.638298 (-6852 2450);
PAINT MONO (-6852 2450);
FORCEPROP 2 LAST $XR1 133 
J 0
(-6972 2450);
DISPLAY 0.638298 (-6972 2450);
PAINT MONO (-6972 2450);
FORCEPROP 2 LAST CDS_LIB mstr_standard
J 0
(-6600 2450);
PAINT MONO (-6600 2450);
DISPLAY INVISIBLE (-6600 2450);
FORCEPROP 1 LAST OFFPAGE TRUE
J 0
(-6275 2325);
DISPLAY 0.872340 (-6275 2325);
PAINT GREEN (-6275 2325);
DISPLAY INVISIBLE (-6275 2325);
FORCEPROP 1 LAST COMMENT_BODY TRUE
J 0
(-6475 2350);
DISPLAY 0.872340 (-6475 2350);
PAINT GREEN (-6475 2350);
DISPLAY INVISIBLE (-6475 2350);
FORCEPROP 2 LAST PATH I54
J 0
(-6550 2525);
DISPLAY 1.021277 (-6550 2525);
PAINT ORANGE (-6550 2525);
DISPLAY INVISIBLE (-6550 2525);
FORCEADD OFFPAGE..1
(-6600 2400);
FORCEPROP 2 LAST $XR0 108 
J 0
(-6852 2400);
DISPLAY 0.638298 (-6852 2400);
PAINT MONO (-6852 2400);
FORCEPROP 2 LAST $XR1 133 
J 0
(-6972 2400);
DISPLAY 0.638298 (-6972 2400);
PAINT MONO (-6972 2400);
FORCEPROP 2 LAST CDS_LIB mstr_standard
J 0
(-6600 2400);
PAINT MONO (-6600 2400);
DISPLAY INVISIBLE (-6600 2400);
FORCEPROP 1 LAST OFFPAGE TRUE
J 0
(-6275 2275);
DISPLAY 0.872340 (-6275 2275);
PAINT GREEN (-6275 2275);
DISPLAY INVISIBLE (-6275 2275);
FORCEPROP 1 LAST COMMENT_BODY TRUE
J 0
(-6475 2300);
DISPLAY 0.872340 (-6475 2300);
PAINT GREEN (-6475 2300);
DISPLAY INVISIBLE (-6475 2300);
FORCEPROP 2 LAST PATH I55
J 0
(-6550 2475);
DISPLAY 1.021277 (-6550 2475);
PAINT ORANGE (-6550 2475);
DISPLAY INVISIBLE (-6550 2475);
FORCEADD OFFPAGE..2
(-1375 3300);
FORCEPROP 2 LAST $XR0 125 
J 0
(-1186 3300);
DISPLAY 0.638298 (-1186 3300);
PAINT MONO (-1186 3300);
FORCEPROP 2 LAST $XR1 154 
J 0
(-1066 3300);
DISPLAY 0.638298 (-1066 3300);
PAINT MONO (-1066 3300);
FORCEPROP 2 LAST CDS_LIB mstr_standard
J 0
(-1375 3300);
PAINT ORANGE (-1375 3300);
DISPLAY INVISIBLE (-1375 3300);
FORCEPROP 1 LAST OFFPAGE TRUE
J 0
(-1050 3175);
DISPLAY 0.872340 (-1050 3175);
PAINT GREEN (-1050 3175);
DISPLAY INVISIBLE (-1050 3175);
FORCEPROP 1 LAST COMMENT_BODY TRUE
J 0
(-1420 3205);
DISPLAY 0.872340 (-1420 3205);
PAINT GREEN (-1420 3205);
DISPLAY INVISIBLE (-1420 3205);
FORCEPROP 2 LAST PATH I6
J 0
(-1200 3375);
DISPLAY 1.021277 (-1200 3375);
PAINT ORANGE (-1200 3375);
DISPLAY INVISIBLE (-1200 3375);
FORCEADD OFFPAGE..2
(-1375 3250);
FORCEPROP 2 LAST $XR0 111 
J 0
(-1186 3250);
DISPLAY 0.638298 (-1186 3250);
PAINT MONO (-1186 3250);
FORCEPROP 2 LAST $XR1 125 
J 0
(-1066 3250);
DISPLAY 0.638298 (-1066 3250);
PAINT MONO (-1066 3250);
FORCEPROP 2 LAST $XR2 154 
J 0
(-946 3250);
DISPLAY 0.638298 (-946 3250);
PAINT MONO (-946 3250);
FORCEPROP 2 LAST CDS_LIB mstr_standard
J 0
(-1375 3250);
PAINT ORANGE (-1375 3250);
DISPLAY INVISIBLE (-1375 3250);
FORCEPROP 1 LAST OFFPAGE TRUE
J 0
(-1050 3125);
DISPLAY 0.872340 (-1050 3125);
PAINT GREEN (-1050 3125);
DISPLAY INVISIBLE (-1050 3125);
FORCEPROP 1 LAST COMMENT_BODY TRUE
J 0
(-1420 3155);
DISPLAY 0.872340 (-1420 3155);
PAINT GREEN (-1420 3155);
DISPLAY INVISIBLE (-1420 3155);
FORCEPROP 2 LAST PATH I7
J 0
(-1200 3325);
DISPLAY 1.021277 (-1200 3325);
PAINT ORANGE (-1200 3325);
DISPLAY INVISIBLE (-1200 3325);
FORCEADD OFFPAGE..2
(-7325 1175);
FORCEPROP 2 LAST $XR0 101 
J 0
(-7136 1175);
DISPLAY 0.638298 (-7136 1175);
PAINT MONO (-7136 1175);
FORCEPROP 2 LAST $XR1 121 
J 0
(-7016 1175);
DISPLAY 0.638298 (-7016 1175);
PAINT MONO (-7016 1175);
FORCEPROP 2 LAST PATH I72
J 0
(-7150 1250);
DISPLAY 1.021277 (-7150 1250);
PAINT ORANGE (-7150 1250);
DISPLAY INVISIBLE (-7150 1250);
FORCEPROP 1 LAST COMMENT_BODY TRUE
J 0
(-7370 1080);
DISPLAY 0.872340 (-7370 1080);
PAINT GREEN (-7370 1080);
DISPLAY INVISIBLE (-7370 1080);
FORCEPROP 1 LAST OFFPAGE TRUE
J 0
(-7000 1050);
DISPLAY 0.872340 (-7000 1050);
PAINT GREEN (-7000 1050);
DISPLAY INVISIBLE (-7000 1050);
FORCEPROP 2 LAST CDS_LIB mstr_standard
J 0
(-7325 1175);
PAINT ORANGE (-7325 1175);
DISPLAY INVISIBLE (-7325 1175);
FORCEADD RES..2
(-8125 950);
FORCEPROP 1 LAST PART_NUMBER G21796-016
J 0
(-8085 825);
DISPLAY 0.617021 (-8085 825);
PAINT BLUE (-8085 825);
FORCEPROP 1 LAST VALUE 10.0K
J 0
(-8080 1025);
DISPLAY 0.617021 (-8080 1025);
PAINT SKYBLUE (-8080 1025);
FORCEPROP 1 LAST TOLERANCE 1%
J 0
(-8080 975);
DISPLAY 0.617021 (-8080 975);
PAINT SKYBLUE (-8080 975);
FORCEPROP 1 LAST PACK_TYPE 0402
J 0
(-8085 775);
DISPLAY 0.617021 (-8085 775);
PAINT SKYBLUE (-8085 775);
FORCEPROP 1 LAST MATERIAL CHIP
J 0
(-8085 875);
DISPLAY 0.617021 (-8085 875);
PAINT SKYBLUE (-8085 875);
FORCEPROP 1 LAST WATTAGE 1/16W
J 0
(-8085 925);
DISPLAY 0.617021 (-8085 925);
PAINT SKYBLUE (-8085 925);
FORCEPROP 1 LASTPIN (-8125 850) $PN 2
J 0
(-8120 860);
DISPLAY 0.617021 (-8120 860);
PAINT ORANGE (-8120 860);
FORCEPROP 1 LASTPIN (-8125 1050) $PN 1
J 0
(-8120 1012);
DISPLAY 0.617021 (-8120 1012);
PAINT ORANGE (-8120 1012);
FORCEPROP 1 LAST LOCATION R7C20
J 0
(-8080 1075);
DISPLAY 0.617021 (-8080 1075);
PAINT AQUA (-8080 1075);
FORCEPROP 2 LAST ROOM NIC_SPRV
J 0
(-8075 1125);
DISPLAY 1.021277 (-8075 1125);
PAINT ORANGE (-8075 1125);
DISPLAY INVISIBLE (-8075 1125);
FORCEPROP 2 LAST CDS_LOCATION R7C20
J 0
(-8080 1075);
DISPLAY 0.617021 (-8080 1075);
PAINT AQUA (-8080 1075);
DISPLAY INVISIBLE (-8080 1075);
FORCEPROP 2 LAST SEC 1
J 0
(-8075 1175);
DISPLAY 0.680851 (-8075 1175);
PAINT MONO (-8075 1175);
DISPLAY INVISIBLE (-8075 1175);
FORCEPROP 2 LAST BOM_COST NT_GBE_BASE
J 0
(-8075 1175);
DISPLAY 1.021277 (-8075 1175);
PAINT ORANGE (-8075 1175);
DISPLAY INVISIBLE (-8075 1175);
FORCEPROP 2 LAST SEC_TYPE 0402
J 0
(-8075 1175);
DISPLAY 1.021277 (-8075 1175);
PAINT ORANGE (-8075 1175);
DISPLAY INVISIBLE (-8075 1175);
FORCEPROP 2 LAST CDS_LIB mstr_discrete
J 0
(-8125 950);
PAINT ORANGE (-8125 950);
DISPLAY INVISIBLE (-8125 950);
FORCEPROP 1 LAST PATH I73
J 0
(-8075 1125);
DISPLAY 0.978723 (-8075 1125);
PAINT WHITE (-8075 1125);
DISPLAY INVISIBLE (-8075 1125);
FORCEADD GND..1
(-8125 675);
FORCEPROP 3 LASTPIN (-8125 725) SIG_NAME GND\g
J 0
(-8115 735);
DISPLAY 0.659574 (-8115 735);
PAINT MONO (-8115 735);
DISPLAY INVISIBLE (-8115 735);
FORCEPROP 1 LAST VOLTAGE 0.0V
J 0
(-8170 632);
DISPLAY 0.340426 (-8170 632);
PAINT SKYBLUE (-8170 632);
DISPLAY INVISIBLE (-8170 632);
FORCEPROP 1 LAST HDL_POWER GND
J 0
(-8125 825);
DISPLAY 0.872340 (-8125 825);
PAINT GREEN (-8125 825);
DISPLAY INVISIBLE (-8125 825);
FORCEPROP 1 LAST SIZE 1B
J 0
(-8050 625);
DISPLAY 0.872340 (-8050 625);
PAINT AQUA (-8050 625);
DISPLAY INVISIBLE (-8050 625);
FORCEPROP 2 LAST CDS_LIB mstr_symbols
J 0
(-8125 675);
PAINT ORANGE (-8125 675);
DISPLAY INVISIBLE (-8125 675);
FORCEPROP 1 LAST BODY_TYPE PLUMBING
J 0
(-8170 632);
DISPLAY 0.340426 (-8170 632);
PAINT GREEN (-8170 632);
DISPLAY INVISIBLE (-8170 632);
FORCEPROP 1 LAST PATH I74
J 0
(-8050 675);
DISPLAY 0.872340 (-8050 675);
PAINT AQUA (-8050 675);
DISPLAY INVISIBLE (-8050 675);
FORCEADD OFFPAGE..1
(-6600 3050);
FORCEPROP 2 LAST $XR0 152 
J 0
(-6852 3050);
DISPLAY 0.638298 (-6852 3050);
PAINT MONO (-6852 3050);
FORCEPROP 2 LAST CDS_LIB mstr_standard
J 0
(-6600 3050);
PAINT ORANGE (-6600 3050);
DISPLAY INVISIBLE (-6600 3050);
FORCEPROP 1 LAST OFFPAGE TRUE
J 0
(-6275 2925);
DISPLAY 0.872340 (-6275 2925);
PAINT GREEN (-6275 2925);
DISPLAY INVISIBLE (-6275 2925);
FORCEPROP 1 LAST COMMENT_BODY TRUE
J 0
(-6475 2950);
DISPLAY 0.872340 (-6475 2950);
PAINT GREEN (-6475 2950);
DISPLAY INVISIBLE (-6475 2950);
FORCEPROP 2 LAST PATH I75
J 0
(-6875 3100);
DISPLAY 1.021277 (-6875 3100);
PAINT ORANGE (-6875 3100);
DISPLAY INVISIBLE (-6875 3100);
FORCEADD OFFPAGE..1
(-6600 2900);
FORCEPROP 2 LAST $XR0 152 
J 0
(-6852 2900);
DISPLAY 0.638298 (-6852 2900);
PAINT MONO (-6852 2900);
FORCEPROP 2 LAST CDS_LIB mstr_standard
J 0
(-6600 2900);
PAINT ORANGE (-6600 2900);
DISPLAY INVISIBLE (-6600 2900);
FORCEPROP 1 LAST OFFPAGE TRUE
J 0
(-6275 2775);
DISPLAY 0.872340 (-6275 2775);
PAINT GREEN (-6275 2775);
DISPLAY INVISIBLE (-6275 2775);
FORCEPROP 1 LAST COMMENT_BODY TRUE
J 0
(-6475 2800);
DISPLAY 0.872340 (-6475 2800);
PAINT GREEN (-6475 2800);
DISPLAY INVISIBLE (-6475 2800);
FORCEPROP 2 LAST PATH I76
J 0
(-6850 2950);
DISPLAY 1.021277 (-6850 2950);
PAINT ORANGE (-6850 2950);
DISPLAY INVISIBLE (-6850 2950);
FORCEADD OFFPAGE..1
(-6600 2950);
FORCEPROP 2 LAST $XR0 152 
J 0
(-6852 2950);
DISPLAY 0.638298 (-6852 2950);
PAINT MONO (-6852 2950);
FORCEPROP 2 LAST CDS_LIB mstr_standard
J 0
(-6600 2950);
PAINT ORANGE (-6600 2950);
DISPLAY INVISIBLE (-6600 2950);
FORCEPROP 1 LAST OFFPAGE TRUE
J 0
(-6275 2825);
DISPLAY 0.872340 (-6275 2825);
PAINT GREEN (-6275 2825);
DISPLAY INVISIBLE (-6275 2825);
FORCEPROP 1 LAST COMMENT_BODY TRUE
J 0
(-6475 2850);
DISPLAY 0.872340 (-6475 2850);
PAINT GREEN (-6475 2850);
DISPLAY INVISIBLE (-6475 2850);
FORCEPROP 2 LAST PATH I77
J 0
(-6850 3000);
DISPLAY 1.021277 (-6850 3000);
PAINT ORANGE (-6850 3000);
DISPLAY INVISIBLE (-6850 3000);
FORCEADD OFFPAGE..1
(-6600 3000);
FORCEPROP 2 LAST $XR0 152 
J 0
(-6852 3000);
DISPLAY 0.638298 (-6852 3000);
PAINT MONO (-6852 3000);
FORCEPROP 2 LAST CDS_LIB mstr_standard
J 0
(-6600 3000);
PAINT ORANGE (-6600 3000);
DISPLAY INVISIBLE (-6600 3000);
FORCEPROP 1 LAST OFFPAGE TRUE
J 0
(-6275 2875);
DISPLAY 0.872340 (-6275 2875);
PAINT GREEN (-6275 2875);
DISPLAY INVISIBLE (-6275 2875);
FORCEPROP 1 LAST COMMENT_BODY TRUE
J 0
(-6475 2900);
DISPLAY 0.872340 (-6475 2900);
PAINT GREEN (-6475 2900);
DISPLAY INVISIBLE (-6475 2900);
FORCEPROP 2 LAST PATH I78
J 0
(-6875 3050);
DISPLAY 1.021277 (-6875 3050);
PAINT ORANGE (-6875 3050);
DISPLAY INVISIBLE (-6875 3050);
FORCEADD OFFPAGE..1
(-6600 3250);
FORCEPROP 2 LAST $XR0 93 
J 0
(-6821 3250);
DISPLAY 0.638298 (-6821 3250);
PAINT MONO (-6821 3250);
FORCEPROP 2 LAST CDS_LIB mstr_standard
J 0
(-6600 3250);
PAINT ORANGE (-6600 3250);
DISPLAY INVISIBLE (-6600 3250);
FORCEPROP 1 LAST OFFPAGE TRUE
J 0
(-6275 3125);
PAINT GREEN (-6275 3125);
DISPLAY INVISIBLE (-6275 3125);
FORCEPROP 1 LAST COMMENT_BODY TRUE
J 0
(-6475 3150);
DISPLAY 1.404255 (-6475 3150);
PAINT PEACH (-6475 3150);
DISPLAY INVISIBLE (-6475 3150);
FORCEPROP 2 LAST PATH I79
J 0
(-6850 3300);
DISPLAY 1.021277 (-6850 3300);
PAINT ORANGE (-6850 3300);
DISPLAY INVISIBLE (-6850 3300);
FORCEADD OFFPAGE..4
(-1375 3200);
FORCEPROP 2 LAST $XR0 154 
J 0
(-1189 3200);
DISPLAY 0.638298 (-1189 3200);
PAINT MONO (-1189 3200);
FORCEPROP 2 LAST $XR1 184 
J 0
(-1069 3200);
DISPLAY 0.638298 (-1069 3200);
PAINT MONO (-1069 3200);
FORCEPROP 2 LAST CDS_LIB mstr_standard
J 0
(-1375 3200);
PAINT ORANGE (-1375 3200);
DISPLAY INVISIBLE (-1375 3200);
FORCEPROP 1 LAST OFFPAGE TRUE
J 0
(-1050 3075);
DISPLAY 0.872340 (-1050 3075);
PAINT GREEN (-1050 3075);
DISPLAY INVISIBLE (-1050 3075);
FORCEPROP 1 LAST COMMENT_BODY TRUE
J 0
(-1400 3100);
DISPLAY 0.872340 (-1400 3100);
PAINT GREEN (-1400 3100);
DISPLAY INVISIBLE (-1400 3100);
FORCEPROP 2 LAST PATH I8
J 0
(-1200 3275);
DISPLAY 1.021277 (-1200 3275);
PAINT ORANGE (-1200 3275);
DISPLAY INVISIBLE (-1200 3275);
FORCEADD OFFPAGE..1
(-6600 3200);
FORCEPROP 2 LAST $XR0 93 
J 0
(-6821 3200);
DISPLAY 0.638298 (-6821 3200);
PAINT MONO (-6821 3200);
FORCEPROP 2 LAST CDS_LIB mstr_standard
J 0
(-6600 3200);
PAINT ORANGE (-6600 3200);
DISPLAY INVISIBLE (-6600 3200);
FORCEPROP 1 LAST OFFPAGE TRUE
J 0
(-6275 3075);
PAINT GREEN (-6275 3075);
DISPLAY INVISIBLE (-6275 3075);
FORCEPROP 1 LAST COMMENT_BODY TRUE
J 0
(-6475 3100);
DISPLAY 1.404255 (-6475 3100);
PAINT PEACH (-6475 3100);
DISPLAY INVISIBLE (-6475 3100);
FORCEPROP 2 LAST PATH I80
J 0
(-6800 3250);
DISPLAY 1.021277 (-6800 3250);
PAINT ORANGE (-6800 3250);
DISPLAY INVISIBLE (-6800 3250);
FORCEADD OFFPAGE..1
(-6600 3100);
FORCEPROP 2 LAST $XR0 93 
J 0
(-6821 3100);
DISPLAY 0.638298 (-6821 3100);
PAINT MONO (-6821 3100);
FORCEPROP 2 LAST CDS_LIB mstr_standard
J 0
(-6600 3100);
PAINT MONO (-6600 3100);
DISPLAY INVISIBLE (-6600 3100);
FORCEPROP 1 LAST OFFPAGE TRUE
J 0
(-6275 2975);
PAINT GREEN (-6275 2975);
DISPLAY INVISIBLE (-6275 2975);
FORCEPROP 1 LAST COMMENT_BODY TRUE
J 0
(-6475 3000);
DISPLAY 1.404255 (-6475 3000);
PAINT PEACH (-6475 3000);
DISPLAY INVISIBLE (-6475 3000);
FORCEPROP 2 LAST PATH I85
J 0
(-6800 3150);
DISPLAY 1.021277 (-6800 3150);
PAINT ORANGE (-6800 3150);
DISPLAY INVISIBLE (-6800 3150);
FORCEADD OFFPAGE..1
(-6600 3150);
FORCEPROP 2 LAST $XR0 93 
J 0
(-6821 3150);
DISPLAY 0.638298 (-6821 3150);
PAINT MONO (-6821 3150);
FORCEPROP 2 LAST CDS_LIB mstr_standard
J 0
(-6600 3150);
PAINT MONO (-6600 3150);
DISPLAY INVISIBLE (-6600 3150);
FORCEPROP 1 LAST OFFPAGE TRUE
J 0
(-6275 3025);
PAINT GREEN (-6275 3025);
DISPLAY INVISIBLE (-6275 3025);
FORCEPROP 1 LAST COMMENT_BODY TRUE
J 0
(-6475 3050);
DISPLAY 1.404255 (-6475 3050);
PAINT PEACH (-6475 3050);
DISPLAY INVISIBLE (-6475 3050);
FORCEPROP 2 LAST PATH I86
J 0
(-6850 3200);
DISPLAY 1.021277 (-6850 3200);
PAINT ORANGE (-6850 3200);
DISPLAY INVISIBLE (-6850 3200);
FORCEADD OFFPAGE..1
(-6600 2750);
FORCEPROP 2 LAST $XR2 145 
J 0
(-6972 2750);
DISPLAY 0.638298 (-6972 2750);
PAINT MONO (-6972 2750);
FORCEPROP 2 LAST $XR0 133 
J 0
(-6852 2750);
DISPLAY 0.638298 (-6852 2750);
PAINT MONO (-6852 2750);
FORCEPROP 2 LAST $XR1 188 
J 0
(-6972 2750);
DISPLAY 0.638298 (-6972 2750);
PAINT MONO (-6972 2750);
FORCEPROP 2 LAST CDS_LIB mstr_standard
J 0
(-6600 2750);
PAINT ORANGE (-6600 2750);
DISPLAY INVISIBLE (-6600 2750);
FORCEPROP 1 LAST OFFPAGE TRUE
J 0
(-6275 2625);
DISPLAY 0.872340 (-6275 2625);
PAINT GREEN (-6275 2625);
DISPLAY INVISIBLE (-6275 2625);
FORCEPROP 1 LAST COMMENT_BODY TRUE
J 0
(-6475 2650);
DISPLAY 0.872340 (-6475 2650);
PAINT GREEN (-6475 2650);
DISPLAY INVISIBLE (-6475 2650);
FORCEPROP 2 LAST PATH I87
J 0
(-6550 2825);
DISPLAY 1.021277 (-6550 2825);
PAINT ORANGE (-6550 2825);
DISPLAY INVISIBLE (-6550 2825);
FORCEADD OFFPAGE..1
(-6600 2700);
FORCEPROP 2 LAST $XR2 145 
J 0
(-6972 2700);
DISPLAY 0.638298 (-6972 2700);
PAINT MONO (-6972 2700);
FORCEPROP 2 LAST $XR0 133 
J 0
(-6852 2700);
DISPLAY 0.638298 (-6852 2700);
PAINT MONO (-6852 2700);
FORCEPROP 2 LAST $XR1 187 
J 0
(-6972 2700);
DISPLAY 0.638298 (-6972 2700);
PAINT MONO (-6972 2700);
FORCEPROP 2 LAST CDS_LIB mstr_standard
J 0
(-6600 2700);
PAINT ORANGE (-6600 2700);
DISPLAY INVISIBLE (-6600 2700);
FORCEPROP 1 LAST OFFPAGE TRUE
J 0
(-6275 2575);
DISPLAY 0.872340 (-6275 2575);
PAINT GREEN (-6275 2575);
DISPLAY INVISIBLE (-6275 2575);
FORCEPROP 1 LAST COMMENT_BODY TRUE
J 0
(-6475 2600);
DISPLAY 0.872340 (-6475 2600);
PAINT GREEN (-6475 2600);
DISPLAY INVISIBLE (-6475 2600);
FORCEPROP 2 LAST PATH I88
J 0
(-6550 2775);
DISPLAY 1.021277 (-6550 2775);
PAINT ORANGE (-6550 2775);
DISPLAY INVISIBLE (-6550 2775);
FORCEADD RES..1
(-5100 550);
FORCEPROP 1 LAST LOCATION R3P3
J 0
(-5150 600);
DISPLAY 0.617021 (-5150 600);
PAINT AQUA (-5150 600);
FORCEPROP 1 LAST VALUE 0.0
J 2
(-5200 550);
DISPLAY 0.617021 (-5200 550);
PAINT SKYBLUE (-5200 550);
FORCEPROP 1 LAST TOLERANCE 5%
J 0
(-5125 500);
DISPLAY 0.617021 (-5125 500);
PAINT SKYBLUE (-5125 500);
FORCEPROP 1 LASTPIN (-5200 550) $PN 1
J 0
(-5188 562);
DISPLAY 0.617021 (-5188 562);
PAINT ORANGE (-5188 562);
FORCEPROP 1 LASTPIN (-5000 550) $PN 2
J 0
(-5038 562);
DISPLAY 0.617021 (-5038 562);
PAINT ORANGE (-5038 562);
FORCEPROP 1 LAST PACK_TYPE 0402
J 0
(-4900 500);
DISPLAY 0.617021 (-4900 500);
PAINT SKYBLUE (-4900 500);
FORCEPROP 1 LAST MATERIAL CHIP
J 0
(-5025 500);
DISPLAY 0.617021 (-5025 500);
PAINT SKYBLUE (-5025 500);
FORCEPROP 1 LAST PART_NUMBER G21497-005
J 0
(-5350 500);
DISPLAY 0.617021 (-5350 500);
PAINT BLUE (-5350 500);
FORCEPROP 1 LAST WATTAGE 1/16W
J 2
(-4875 550);
DISPLAY 0.617021 (-4875 550);
PAINT SKYBLUE (-4875 550);
DISPLAY INVISIBLE (-4875 550);
FORCEPROP 1 LAST PATH I89
J 0
(-5150 700);
DISPLAY 0.978723 (-5150 700);
PAINT WHITE (-5150 700);
DISPLAY INVISIBLE (-5150 700);
FORCEPROP 0 LAST CDS_SEC 1
J 0
(-4975 600);
PAINT ORANGE (-4975 600);
DISPLAY INVISIBLE (-4975 600);
FORCEPROP 2 LAST CDS_LOCATION R3P3
J 0
(-5400 550);
DISPLAY 0.617021 (-5400 550);
PAINT AQUA (-5400 550);
DISPLAY INVISIBLE (-5400 550);
FORCEPROP 2 LAST SEC 1
J 0
(-5150 750);
DISPLAY 0.680851 (-5150 750);
PAINT MONO (-5150 750);
DISPLAY INVISIBLE (-5150 750);
FORCEPROP 2 LAST CDS_LIB mstr_discrete
J 0
(-5100 550);
PAINT ORANGE (-5100 550);
DISPLAY INVISIBLE (-5100 550);
FORCEPROP 2 LAST SEC_TYPE 0402
J 0
(-5150 750);
DISPLAY 1.021277 (-5150 750);
PAINT ORANGE (-5150 750);
DISPLAY INVISIBLE (-5150 750);
FORCEADD RES..1
(-5100 850);
FORCEPROP 1 LAST VALUE 0.0
J 2
(-5200 850);
DISPLAY 0.617021 (-5200 850);
PAINT SKYBLUE (-5200 850);
FORCEPROP 1 LAST TOLERANCE 5%
J 0
(-5125 800);
DISPLAY 0.617021 (-5125 800);
PAINT SKYBLUE (-5125 800);
FORCEPROP 1 LAST PACK_TYPE 0402
J 0
(-4900 800);
DISPLAY 0.617021 (-4900 800);
PAINT SKYBLUE (-4900 800);
FORCEPROP 1 LAST MATERIAL CHIP
J 0
(-5025 800);
DISPLAY 0.617021 (-5025 800);
PAINT SKYBLUE (-5025 800);
FORCEPROP 1 LASTPIN (-5000 850) $PN 2
J 0
(-5038 862);
DISPLAY 0.617021 (-5038 862);
PAINT ORANGE (-5038 862);
FORCEPROP 1 LASTPIN (-5200 850) $PN 1
J 0
(-5188 862);
DISPLAY 0.617021 (-5188 862);
PAINT ORANGE (-5188 862);
FORCEPROP 1 LAST LOCATION R3P2
J 0
(-5150 900);
DISPLAY 0.617021 (-5150 900);
PAINT AQUA (-5150 900);
FORCEPROP 1 LAST PART_NUMBER G21497-005
J 0
(-5350 800);
DISPLAY 0.617021 (-5350 800);
PAINT BLUE (-5350 800);
FORCEPROP 1 LAST WATTAGE 1/16W
J 2
(-4875 850);
DISPLAY 0.617021 (-4875 850);
PAINT SKYBLUE (-4875 850);
DISPLAY INVISIBLE (-4875 850);
FORCEPROP 2 LAST SEC_TYPE 0402
J 0
(-5150 1050);
DISPLAY 1.021277 (-5150 1050);
PAINT ORANGE (-5150 1050);
DISPLAY INVISIBLE (-5150 1050);
FORCEPROP 2 LAST CDS_LIB mstr_discrete
J 0
(-5100 850);
PAINT ORANGE (-5100 850);
DISPLAY INVISIBLE (-5100 850);
FORCEPROP 2 LAST SEC 1
J 0
(-5150 1050);
DISPLAY 0.680851 (-5150 1050);
PAINT MONO (-5150 1050);
DISPLAY INVISIBLE (-5150 1050);
FORCEPROP 2 LAST CDS_LOCATION R3P2
J 0
(-5150 900);
DISPLAY 0.617021 (-5150 900);
PAINT AQUA (-5150 900);
DISPLAY INVISIBLE (-5150 900);
FORCEPROP 0 LAST CDS_SEC 1
J 0
(-5150 950);
PAINT ORANGE (-5150 950);
DISPLAY INVISIBLE (-5150 950);
FORCEPROP 1 LAST PATH I90
J 0
(-5150 1000);
DISPLAY 0.978723 (-5150 1000);
PAINT WHITE (-5150 1000);
DISPLAY INVISIBLE (-5150 1000);
FORCEADD RES..1
(-5100 700);
FORCEPROP 1 LAST LOCATION R2P1
J 0
(-5150 750);
DISPLAY 0.617021 (-5150 750);
PAINT AQUA (-5150 750);
FORCEPROP 1 LAST PART_NUMBER G21497-005
J 0
(-5350 650);
DISPLAY 0.617021 (-5350 650);
PAINT BLUE (-5350 650);
FORCEPROP 1 LAST VALUE 0.0
J 2
(-5200 700);
DISPLAY 0.617021 (-5200 700);
PAINT SKYBLUE (-5200 700);
FORCEPROP 1 LAST TOLERANCE 5%
J 0
(-5125 650);
DISPLAY 0.617021 (-5125 650);
PAINT SKYBLUE (-5125 650);
FORCEPROP 1 LAST MATERIAL CHIP
J 0
(-5025 650);
DISPLAY 0.617021 (-5025 650);
PAINT SKYBLUE (-5025 650);
FORCEPROP 1 LASTPIN (-5200 700) $PN 1
J 0
(-5188 712);
DISPLAY 0.617021 (-5188 712);
PAINT ORANGE (-5188 712);
FORCEPROP 1 LASTPIN (-5000 700) $PN 2
J 0
(-5038 712);
DISPLAY 0.617021 (-5038 712);
PAINT ORANGE (-5038 712);
FORCEPROP 1 LAST PACK_TYPE 0402
J 0
(-4900 650);
DISPLAY 0.617021 (-4900 650);
PAINT SKYBLUE (-4900 650);
FORCEPROP 1 LAST WATTAGE 1/16W
J 2
(-4875 700);
DISPLAY 0.617021 (-4875 700);
PAINT SKYBLUE (-4875 700);
DISPLAY INVISIBLE (-4875 700);
FORCEPROP 1 LAST PATH I91
J 0
(-5150 850);
DISPLAY 0.978723 (-5150 850);
PAINT WHITE (-5150 850);
DISPLAY INVISIBLE (-5150 850);
FORCEPROP 0 LAST CDS_SEC 1
J 0
(-4975 750);
PAINT ORANGE (-4975 750);
DISPLAY INVISIBLE (-4975 750);
FORCEPROP 2 LAST CDS_LOCATION R2P1
J 0
(-5400 700);
DISPLAY 0.617021 (-5400 700);
PAINT AQUA (-5400 700);
DISPLAY INVISIBLE (-5400 700);
FORCEPROP 2 LAST SEC 1
J 0
(-5150 900);
DISPLAY 0.680851 (-5150 900);
PAINT MONO (-5150 900);
DISPLAY INVISIBLE (-5150 900);
FORCEPROP 2 LAST CDS_LIB mstr_discrete
J 0
(-5100 700);
PAINT ORANGE (-5100 700);
DISPLAY INVISIBLE (-5100 700);
FORCEPROP 2 LAST SEC_TYPE 0402
J 0
(-5150 900);
DISPLAY 1.021277 (-5150 900);
PAINT ORANGE (-5150 900);
DISPLAY INVISIBLE (-5150 900);
FORCEADD OFFPAGE..2
R 2
(-6050 850);
FORCEPROP 2 LAST $XR0 139 
J 0
(-6335 850);
DISPLAY 0.638298 (-6335 850);
PAINT MONO (-6335 850);
FORCEPROP 2 LAST $XR1 147 
J 0
(-6455 850);
DISPLAY 0.638298 (-6455 850);
PAINT MONO (-6455 850);
FORCEPROP 2 LAST PATH I92
J 0
(-6300 900);
DISPLAY 1.021277 (-6300 900);
PAINT ORANGE (-6300 900);
DISPLAY INVISIBLE (-6300 900);
FORCEPROP 2 LAST CDS_LIB mstr_standard
J 0
(-6050 850);
PAINT ORANGE (-6050 850);
DISPLAY INVISIBLE (-6050 850);
FORCEPROP 1 LAST OFFPAGE TRUE
J 2
(-6375 725);
DISPLAY 0.872340 (-6375 725);
PAINT GREEN (-6375 725);
DISPLAY INVISIBLE (-6375 725);
FORCEPROP 1 LAST COMMENT_BODY TRUE
J 2
(-6005 755);
DISPLAY 0.872340 (-6005 755);
PAINT GREEN (-6005 755);
DISPLAY INVISIBLE (-6005 755);
FORCEADD OFFPAGE..5
(-6050 700);
FORCEPROP 2 LAST $XR0 139 
J 0
(-6335 700);
DISPLAY 0.638298 (-6335 700);
PAINT MONO (-6335 700);
FORCEPROP 2 LAST $XR1 147 
J 0
(-6455 700);
DISPLAY 0.638298 (-6455 700);
PAINT MONO (-6455 700);
FORCEPROP 2 LAST PATH I93
J 0
(-6300 750);
DISPLAY 1.021277 (-6300 750);
PAINT ORANGE (-6300 750);
DISPLAY INVISIBLE (-6300 750);
FORCEPROP 2 LAST CDS_LIB mstr_standard
J 0
(-6050 700);
PAINT ORANGE (-6050 700);
DISPLAY INVISIBLE (-6050 700);
FORCEPROP 1 LAST OFFPAGE TRUE
J 0
(-5725 575);
DISPLAY 0.872340 (-5725 575);
PAINT GREEN (-5725 575);
DISPLAY INVISIBLE (-5725 575);
FORCEPROP 1 LAST COMMENT_BODY TRUE
J 0
(-5950 625);
DISPLAY 0.872340 (-5950 625);
PAINT GREEN (-5950 625);
DISPLAY INVISIBLE (-5950 625);
FORCEADD OFFPAGE..5
(-6050 550);
FORCEPROP 2 LAST $XR0 139 
J 0
(-6335 550);
DISPLAY 0.638298 (-6335 550);
PAINT MONO (-6335 550);
FORCEPROP 2 LAST $XR1 147 
J 0
(-6455 550);
DISPLAY 0.638298 (-6455 550);
PAINT MONO (-6455 550);
FORCEPROP 2 LAST PATH I94
J 0
(-6300 600);
DISPLAY 1.021277 (-6300 600);
PAINT ORANGE (-6300 600);
DISPLAY INVISIBLE (-6300 600);
FORCEPROP 2 LAST CDS_LIB mstr_standard
J 0
(-6050 550);
PAINT ORANGE (-6050 550);
DISPLAY INVISIBLE (-6050 550);
FORCEPROP 1 LAST OFFPAGE TRUE
J 0
(-5725 425);
DISPLAY 0.872340 (-5725 425);
PAINT GREEN (-5725 425);
DISPLAY INVISIBLE (-5725 425);
FORCEPROP 1 LAST COMMENT_BODY TRUE
J 0
(-5950 475);
DISPLAY 0.872340 (-5950 475);
PAINT GREEN (-5950 475);
DISPLAY INVISIBLE (-5950 475);
FORCEADD OFFPAGE..1
(-6600 3500);
FORCEPROP 2 LAST $XR1 147 
J 0
(-6972 3500);
DISPLAY 0.638298 (-6972 3500);
PAINT MONO (-6972 3500);
FORCEPROP 2 LAST $XR2 151 
J 0
(-6972 3500);
DISPLAY 0.638298 (-6972 3500);
PAINT MONO (-6972 3500);
FORCEPROP 2 LAST $XR0 139 
J 0
(-6852 3500);
DISPLAY 0.638298 (-6852 3500);
PAINT MONO (-6852 3500);
FORCEPROP 2 LAST PATH I95
J 0
(-6875 3550);
DISPLAY 1.021277 (-6875 3550);
PAINT ORANGE (-6875 3550);
DISPLAY INVISIBLE (-6875 3550);
FORCEPROP 2 LAST CDS_LIB mstr_standard
J 0
(-6600 3500);
PAINT ORANGE (-6600 3500);
DISPLAY INVISIBLE (-6600 3500);
FORCEPROP 1 LAST OFFPAGE TRUE
J 0
(-6275 3375);
PAINT GREEN (-6275 3375);
DISPLAY INVISIBLE (-6275 3375);
FORCEPROP 1 LAST COMMENT_BODY TRUE
J 0
(-6475 3400);
DISPLAY 1.404255 (-6475 3400);
PAINT PEACH (-6475 3400);
DISPLAY INVISIBLE (-6475 3400);
FORCEADD OFFPAGE..4
R 2
(-6600 3400);
FORCEPROP 2 LAST $XR0 147 
J 0
(-6852 3400);
DISPLAY 0.638298 (-6852 3400);
PAINT MONO (-6852 3400);
FORCEPROP 2 LAST $XR1 139 
J 0
(-6972 3400);
DISPLAY 0.638298 (-6972 3400);
PAINT MONO (-6972 3400);
FORCEPROP 2 LAST PATH I96
J 0
(-6875 3450);
DISPLAY 1.021277 (-6875 3450);
PAINT ORANGE (-6875 3450);
DISPLAY INVISIBLE (-6875 3450);
FORCEPROP 2 LAST CDS_LIB mstr_standard
J 0
(-6600 3400);
PAINT ORANGE (-6600 3400);
DISPLAY INVISIBLE (-6600 3400);
FORCEPROP 1 LAST OFFPAGE TRUE
J 2
(-6925 3275);
DISPLAY 0.872340 (-6925 3275);
PAINT GREEN (-6925 3275);
DISPLAY INVISIBLE (-6925 3275);
FORCEPROP 1 LAST COMMENT_BODY TRUE
J 2
(-6575 3300);
DISPLAY 0.872340 (-6575 3300);
PAINT GREEN (-6575 3300);
DISPLAY INVISIBLE (-6575 3300);
FORCEADD OFFPAGE..4
R 2
(-6600 3450);
FORCEPROP 2 LAST $XR0 147 
J 0
(-6852 3450);
DISPLAY 0.638298 (-6852 3450);
PAINT MONO (-6852 3450);
FORCEPROP 2 LAST $XR1 139 
J 0
(-6972 3450);
DISPLAY 0.638298 (-6972 3450);
PAINT MONO (-6972 3450);
FORCEPROP 2 LAST PATH I97
J 0
(-6875 3500);
DISPLAY 1.021277 (-6875 3500);
PAINT ORANGE (-6875 3500);
DISPLAY INVISIBLE (-6875 3500);
FORCEPROP 2 LAST CDS_LIB mstr_standard
J 2
(-6600 3450);
PAINT ORANGE (-6600 3450);
DISPLAY INVISIBLE (-6600 3450);
FORCEPROP 1 LAST OFFPAGE TRUE
J 2
(-6925 3325);
DISPLAY 0.872340 (-6925 3325);
PAINT GREEN (-6925 3325);
DISPLAY INVISIBLE (-6925 3325);
FORCEPROP 1 LAST COMMENT_BODY TRUE
J 2
(-6575 3350);
DISPLAY 0.872340 (-6575 3350);
PAINT GREEN (-6575 3350);
DISPLAY INVISIBLE (-6575 3350);
FORCEADD RES..1
(-5100 1025);
FORCEPROP 1 LAST VALUE 33.2
J 2
(-5200 1025);
DISPLAY 0.617021 (-5200 1025);
PAINT SKYBLUE (-5200 1025);
FORCEPROP 1 LAST TOLERANCE 1%
J 0
(-5125 975);
DISPLAY 0.617021 (-5125 975);
PAINT SKYBLUE (-5125 975);
FORCEPROP 1 LAST PACK_TYPE 0402
J 0
(-4900 975);
DISPLAY 0.617021 (-4900 975);
PAINT SKYBLUE (-4900 975);
FORCEPROP 1 LASTPIN (-5000 1025) $PN 2
J 0
(-5038 1037);
DISPLAY 0.617021 (-5038 1037);
PAINT ORANGE (-5038 1037);
FORCEPROP 1 LAST MATERIAL CHIP
J 0
(-5025 975);
DISPLAY 0.617021 (-5025 975);
PAINT SKYBLUE (-5025 975);
FORCEPROP 1 LAST LOCATION R7C14
J 0
(-5150 1075);
DISPLAY 0.617021 (-5150 1075);
PAINT AQUA (-5150 1075);
FORCEPROP 1 LASTPIN (-5200 1025) $PN 1
J 0
(-5188 1037);
DISPLAY 0.617021 (-5188 1037);
PAINT ORANGE (-5188 1037);
FORCEPROP 1 LAST PART_NUMBER G21796-074
J 0
(-5350 975);
DISPLAY 0.617021 (-5350 975);
PAINT BLUE (-5350 975);
FORCEPROP 1 LAST WATTAGE 1/16W
J 2
(-5125 875);
DISPLAY 0.617021 (-5125 875);
PAINT SKYBLUE (-5125 875);
DISPLAY INVISIBLE (-5125 875);
FORCEPROP 0 LAST ROOM SB
J 0
(-5050 1125);
DISPLAY 1.021277 (-5050 1125);
PAINT ORANGE (-5050 1125);
DISPLAY INVISIBLE (-5050 1125);
FORCEPROP 2 LAST CDS_LIB mstr_discrete
J 0
(-5100 1025);
PAINT ORANGE (-5100 1025);
DISPLAY INVISIBLE (-5100 1025);
FORCEPROP 2 LAST SEC_TYPE 0402
J 0
(-5150 1225);
DISPLAY 1.021277 (-5150 1225);
PAINT ORANGE (-5150 1225);
DISPLAY INVISIBLE (-5150 1225);
FORCEPROP 2 LAST SEC 1
J 0
(-5150 1225);
DISPLAY 0.680851 (-5150 1225);
PAINT MONO (-5150 1225);
DISPLAY INVISIBLE (-5150 1225);
FORCEPROP 2 LAST CDS_LOCATION R7C14
J 0
(-4900 975);
DISPLAY 0.617021 (-4900 975);
PAINT AQUA (-4900 975);
DISPLAY INVISIBLE (-4900 975);
FORCEPROP 0 LAST CDS_SEC 1
J 0
(-4900 1025);
PAINT ORANGE (-4900 1025);
DISPLAY INVISIBLE (-4900 1025);
FORCEPROP 1 LAST PATH I98
J 0
(-5150 1175);
DISPLAY 0.978723 (-5150 1175);
PAINT WHITE (-5150 1175);
DISPLAY INVISIBLE (-5150 1175);
FORCEADD OFFPAGE..5
(-6050 1025);
FORCEPROP 2 LAST $XR0 125 
J 0
(-6335 1025);
DISPLAY 0.638298 (-6335 1025);
PAINT MONO (-6335 1025);
FORCEPROP 2 LAST $XR1 147 
J 0
(-6455 1025);
DISPLAY 0.638298 (-6455 1025);
PAINT MONO (-6455 1025);
FORCEPROP 2 LAST PATH I99
J 0
(-6325 1075);
DISPLAY 1.021277 (-6325 1075);
PAINT ORANGE (-6325 1075);
DISPLAY INVISIBLE (-6325 1075);
FORCEPROP 2 LAST CDS_LIB mstr_standard
J 0
(-6050 1025);
PAINT ORANGE (-6050 1025);
DISPLAY INVISIBLE (-6050 1025);
FORCEPROP 1 LAST OFFPAGE TRUE
J 0
(-5725 900);
DISPLAY 0.872340 (-5725 900);
PAINT GREEN (-5725 900);
DISPLAY INVISIBLE (-5725 900);
FORCEPROP 1 LAST COMMENT_BODY TRUE
J 0
(-5950 950);
DISPLAY 0.872340 (-5950 950);
PAINT GREEN (-5950 950);
DISPLAY INVISIBLE (-5950 950);
FORCEADD CAD_NOTE..1
(-2325 4350);
FORCEPROP 0 LAST L1 PLACE SPI SERIES RES CLOSE TO PCH
J 0
(-2475 4225);
DISPLAY 1.021277 (-2475 4225);
PAINT ORANGE (-2475 4225);
FORCEPROP 1 LAST COMMENT_BODY TRUE
J 0
(-2300 4450);
DISPLAY 0.978723 (-2300 4450);
PAINT ORANGE (-2300 4450);
DISPLAY INVISIBLE (-2300 4450);
FORCEPROP 2 LAST CDS_LIB mstr_symbols
J 0
(-2325 4350);
PAINT ORANGE (-2325 4350);
DISPLAY INVISIBLE (-2325 4350);
FORCEADD CAD_NOTE..1
(-7550 975);
FORCEPROP 0 LAST L2 RES NEAR PCH
J 0
(-7700 825);
DISPLAY 0.808511 (-7700 825);
PAINT ORANGE (-7700 825);
FORCEPROP 0 LAST L1 PLACE CLK_50M_CKMNG_PCH_10GBE
J 0
(-7700 875);
DISPLAY 0.808511 (-7700 875);
PAINT ORANGE (-7700 875);
FORCEPROP 2 LAST CDS_LIB mstr_symbols
J 0
(-7550 975);
PAINT ORANGE (-7550 975);
DISPLAY INVISIBLE (-7550 975);
FORCEPROP 1 LAST COMMENT_BODY TRUE
J 0
(-7525 1075);
DISPLAY 0.978723 (-7525 1075);
PAINT ORANGE (-7525 1075);
DISPLAY INVISIBLE (-7525 1075);
FORCEADD CAD_NOTE..1
(-7700 4600);
FORCEPROP 0 LAST L5 RMII_BMC_PCH_SRNGVLLE_CRSDV_R1
J 0
(-7850 4300);
DISPLAY 0.808511 (-7850 4300);
PAINT ORANGE (-7850 4300);
FORCEPROP 0 LAST L3 RMII_PCH_SPRNGVLLE_ARB_OUT_R
J 0
(-7850 4400);
DISPLAY 0.808511 (-7850 4400);
PAINT ORANGE (-7850 4400);
FORCEPROP 0 LAST L4 RMII_BMC_PCH_SPRNGVLLE_RXER_R
J 0
(-7850 4350);
DISPLAY 0.808511 (-7850 4350);
PAINT ORANGE (-7850 4350);
FORCEPROP 0 LAST L6 RMII_SPRNGVLLE_BMC_PCH_RXD1_R1
J 0
(-7850 4250);
DISPLAY 0.808511 (-7850 4250);
PAINT ORANGE (-7850 4250);
FORCEPROP 0 LAST L7 RMII_SPRNGVLLE_BMC_PCH_RXD0_R1
J 0
(-7850 4200);
DISPLAY 0.808511 (-7850 4200);
PAINT ORANGE (-7850 4200);
FORCEPROP 0 LAST L2 NETS WITHIN TWO INCHES OF THE PCH:
J 0
(-7850 4450);
DISPLAY 0.808511 (-7850 4450);
PAINT ORANGE (-7850 4450);
FORCEPROP 0 LAST L1 PLACE SERIES RESISTORS ON THE FOLLOWING
J 0
(-7850 4500);
DISPLAY 0.808511 (-7850 4500);
PAINT ORANGE (-7850 4500);
FORCEPROP 1 LAST COMMENT_BODY TRUE
J 0
(-7675 4700);
DISPLAY 0.978723 (-7675 4700);
PAINT ORANGE (-7675 4700);
DISPLAY INVISIBLE (-7675 4700);
FORCEPROP 2 LAST CDS_LIB mstr_symbols
J 0
(-7700 4600);
PAINT ORANGE (-7700 4600);
DISPLAY INVISIBLE (-7700 4600);
FORCEADD INTEL_CORP_BPAGE..1
(-450 0);
FORCEPROP 1 LAST CDS_CON_LAST_MODIFIED Tue Dec 01 11:51:58 2015
J 0
(-1875 325);
DISPLAY 1.340426 (-1875 325);
PAINT ORANGE (-1875 325);
DISPLAY INVISIBLE (-1875 325);
FORCEPROP 1 LAST CUSTOM_TXT_CDS <CURRENT_DESIGN_SHEET> OF <TOTAL_DESIGN_SHEETS>
J 0
(-950 25);
PAINT GREEN (-950 25);
FORCEPROP 1 LAST CUSTOM_TXT_CDS <CON_LAST_MODIFIED>
J 0
(-2375 350);
PAINT GREEN (-2375 350);
FORCEPROP 2 LAST CUSTOM_TXT_CDS <XR_PAGE_TITLE>
J 0
(-8340 5250);
DISPLAY 0.638298 (-8340 5250);
PAINT PINK (-8340 5250);
DISPLAY INVISIBLE (-8340 5250);
FORCEPROP 1 LAST SCH_ADDRESS2 P.O. BOX 58119
J 0
(-4425 75);
DISPLAY 0.617021 (-4425 75);
PAINT GREEN (-4425 75);
FORCEPROP 1 LAST SCH_TITLE LEWISBURG 8/11 RMII, SPI
J 0
(-8400 50);
DISPLAY 1.212766 (-8400 50);
PAINT GREEN (-8400 50);
FORCEPROP 1 LAST SCH_ADDRESS1 2200 Mission College Blvd.
J 0
(-4425 125);
DISPLAY 0.617021 (-4425 125);
PAINT GREEN (-4425 125);
FORCEPROP 1 LAST SCH_ADDRESS3 Santa Clara, CA 95052-8119
J 0
(-4425 25);
DISPLAY 0.617021 (-4425 25);
PAINT GREEN (-4425 25);
FORCEPROP 1 LAST SCH_REV 2.420
J 0
(-700 150);
DISPLAY 0.978723 (-700 150);
PAINT YELLOW (-700 150);
FORCEPROP 1 LAST SCH_DEPT BESD
J 1
(-4900 100);
DISPLAY 1.212766 (-4900 100);
PAINT YELLOW (-4900 100);
FORCEPROP 1 LAST SCH_NUMBER H4694802
J 0
(-1750 150);
DISPLAY 1.212766 (-1750 150);
PAINT YELLOW (-1750 150);
FORCEPROP 1 LAST COMMENT_BODY TRUE
J 0
(-438 12);
DISPLAY 0.638298 (-438 12);
PAINT GREEN (-438 12);
DISPLAY INVISIBLE (-438 12);
FORCEPROP 2 LAST PAGE_BORDER TRUE
J 0
(-8340 5250);
DISPLAY 0.851064 (-8340 5250);
PAINT PINK (-8340 5250);
DISPLAY INVISIBLE (-8340 5250);
FORCEPROP 2 LAST CDS_LIB mstr_symbols
J 0
(-450 0);
PAINT ORANGE (-450 0);
DISPLAY INVISIBLE (-450 0);
FORCEPROP 2 LAST CDS_XR_PAGE_TITLE CR-121 : @BASEBOARD_FAB2_LIB.BASEBOARD_FAB2(SCH_1):PAGE121
J 0
(-8340 5250);
DISPLAY 0.638298 (-8340 5250);
PAINT PINK (-8340 5250);
DISPLAY INVISIBLE (-8340 5250);
WIRE 16 -1 (-7750 3575)(-7750 3500);
WIRE 16 -1 (-8075 2700)(-8075 2625);
WIRE 16 -1 (-8125 850)(-8125 725);
WIRE 16 -1 (-6550 3650)(-5400 3650);
FORCEPROP 2 LAST SIG_NAME RMII_SPRNGVLLE_BMC_PCH_RXD1_R1
J 0
(-6500 3660);
DISPLAY 0.617021 (-6500 3660);
PAINT ORANGE (-6500 3660);
WIRE 16 -1 (-6550 3200)(-5400 3200);
FORCEPROP 2 LAST SIG_NAME FM_CPU_ERR0_PCH_N
J 0
(-6500 3210);
DISPLAY 0.617021 (-6500 3210);
PAINT ORANGE (-6500 3210);
WIRE 16 -1 (-6550 2900)(-5400 2900);
FORCEPROP 2 LAST SIG_NAME H_CPU0_MEMABC_MEMHOT_PCH_N
J 0
(-6500 2910);
DISPLAY 0.617021 (-6500 2910);
PAINT ORANGE (-6500 2910);
WIRE 16 -1 (-6550 3000)(-5400 3000);
FORCEPROP 2 LAST SIG_NAME H_CPU1_MEMGHJ_MEMHOT_PCH_N
J 0
(-6500 3010);
DISPLAY 0.617021 (-6500 3010);
PAINT ORANGE (-6500 3010);
WIRE 16 -1 (-7750 3900)(-5400 3900);
FORCEPROP 0 LAST SIG_NAME A_1P8_3P3_RCOMP
J 0
(-6500 3910);
DISPLAY 0.617021 (-6500 3910);
PAINT ORANGE (-6500 3910);
FORCEPROP 2 LASTPROP $XRERR UNIQUE?
J 0
(-6740 3910);
DISPLAY 0.638298 (-6740 3910);
PAINT MONO (-6740 3910);
DISPLAY INVISIBLE (-6740 3910);
WIRE 16 -1 (-7750 3900)(-7750 3775);
WIRE 16 -1 (-5400 2750)(-6550 2750);
FORCEPROP 2 LAST SIG_NAME FM_OCP_MEZZC_PRES_N
J 0
(-6500 2760);
DISPLAY 0.617021 (-6500 2760);
PAINT ORANGE (-6500 2760);
WIRE 16 -1 (-6550 3150)(-5400 3150);
FORCEPROP 0 LAST SIG_NAME FM_CPU1_PROCHOT_PCH_N
J 0
(-6500 3160);
DISPLAY 0.617021 (-6500 3160);
PAINT ORANGE (-6500 3160);
WIRE 16 -1 (-5400 3400)(-6550 3400);
FORCEPROP 2 LAST SIG_NAME RMII_BMC_PCH_SPRNGVLLE_TXD0
J 0
(-6500 3410);
DISPLAY 0.617021 (-6500 3410);
PAINT ORANGE (-6500 3410);
WIRE 16 -1 (-5400 3450)(-6550 3450);
FORCEPROP 2 LAST SIG_NAME RMII_BMC_PCH_SPRNGVLLE_TXD1
J 0
(-6500 3460);
DISPLAY 0.617021 (-6500 3460);
PAINT ORANGE (-6500 3460);
WIRE 16 -1 (-5400 3500)(-6550 3500);
FORCEPROP 2 LAST SIG_NAME RMII_BMC_PCH_SPRNGVLLE_TXEN
J 0
(-6500 3510);
DISPLAY 0.617021 (-6500 3510);
PAINT ORANGE (-6500 3510);
WIRE 16 -1 (-6550 2600)(-5400 2600);
FORCEPROP 2 LAST SIG_NAME FM_PRSNT_2_5_N
J 0
(-6500 2610);
DISPLAY 0.617021 (-6500 2610);
PAINT ORANGE (-6500 2610);
WIRE 16 -1 (-6550 3350)(-5400 3350);
FORCEPROP 2 LAST SIG_NAME CLK_50M_CKMNG_PCH_10GBE
J 0
(-6500 3360);
DISPLAY 0.617021 (-6500 3360);
PAINT ORANGE (-6500 3360);
WIRE 16 -1 (-6550 3250)(-5400 3250);
FORCEPROP 2 LAST SIG_NAME FM_CPU_ERR1_PCH_N
J 0
(-6500 3260);
DISPLAY 0.617021 (-6500 3260);
PAINT ORANGE (-6500 3260);
WIRE 16 -1 (-6550 3100)(-5400 3100);
FORCEPROP 0 LAST SIG_NAME FM_CPU0_PROCHOT_PCH_N
J 0
(-6500 3110);
DISPLAY 0.617021 (-6500 3110);
PAINT ORANGE (-6500 3110);
WIRE 16 -1 (-6550 3050)(-5400 3050);
FORCEPROP 2 LAST SIG_NAME H_CPU1_MEMKLM_MEMHOT_PCH_N
J 0
(-6500 3060);
DISPLAY 0.617021 (-6500 3060);
PAINT ORANGE (-6500 3060);
WIRE 16 -1 (-6550 2950)(-5400 2950);
FORCEPROP 2 LAST SIG_NAME H_CPU0_MEMDEF_MEMHOT_PCH_N
J 0
(-6500 2960);
DISPLAY 0.617021 (-6500 2960);
PAINT ORANGE (-6500 2960);
WIRE 16 -1 (-5400 2300)(-8075 2300);
FORCEPROP 0 LAST SIG_NAME FM_INTRUDER_HDR_PCH_N
J 0
(-7300 2310);
DISPLAY 0.617021 (-7300 2310);
PAINT ORANGE (-7300 2310);
FORCEPROP 2 LASTPROP $XRERR UNIQUE?
J 0
(-7540 2310);
DISPLAY 0.638298 (-7540 2310);
PAINT MONO (-7540 2310);
DISPLAY INVISIBLE (-7540 2310);
WIRE 16 -1 (-8075 2300)(-8075 2425);
WIRE 16 -1 (-5200 850)(-6000 850);
FORCEPROP 2 LAST SIG_NAME RMII_BMC_PCH_SPRNGVLLE_CRSDV
J 0
(-5975 860);
DISPLAY 0.617021 (-5975 860);
PAINT ORANGE (-5975 860);
WIRE 16 -1 (-8125 1175)(-7375 1175);
FORCEPROP 0 LAST SIG_NAME CLK_50M_CKMNG_PCH_10GBE
J 0
(-7960 1185);
DISPLAY 0.617021 (-7960 1185);
PAINT ORANGE (-7960 1185);
WIRE 16 -1 (-8125 1175)(-8125 1050);
WIRE 16 -1 (-5000 850)(-4175 850);
FORCEPROP 2 LAST SIG_NAME RMII_BMC_PCH_SPRNGVLLE_CRSDV_R1
J 0
(-4900 860);
DISPLAY 0.617021 (-4900 860);
PAINT ORANGE (-4900 860);
WIRE 16 -1 (-6550 3550)(-5400 3550);
FORCEPROP 2 LAST SIG_NAME RMII_BMC_PCH_SPRNGVLLE_CRSDV_R1
J 0
(-6500 3560);
DISPLAY 0.617021 (-6500 3560);
PAINT ORANGE (-6500 3560);
WIRE 16 -1 (-5200 550)(-6000 550);
FORCEPROP 2 LAST SIG_NAME RMII_SPRNGVLLE_BMC_PCH_RXD0
J 0
(-5975 560);
DISPLAY 0.617021 (-5975 560);
PAINT ORANGE (-5975 560);
WIRE 16 -1 (-5000 550)(-4175 550);
FORCEPROP 2 LAST SIG_NAME RMII_SPRNGVLLE_BMC_PCH_RXD0_R1
J 0
(-4900 560);
DISPLAY 0.617021 (-4900 560);
PAINT ORANGE (-4900 560);
WIRE 16 -1 (-6550 3600)(-5400 3600);
FORCEPROP 2 LAST SIG_NAME RMII_SPRNGVLLE_BMC_PCH_RXD0_R1
J 0
(-6500 3610);
DISPLAY 0.617021 (-6500 3610);
PAINT ORANGE (-6500 3610);
WIRE 16 -1 (-5400 3700)(-6550 3700);
FORCEPROP 2 LAST SIG_NAME RMII_BMC_PCH_SPRNGVLLE_RXER_R
J 0
(-6500 3710);
DISPLAY 0.617021 (-6500 3710);
PAINT ORANGE (-6500 3710);
WIRE 16 -1 (-6550 3750)(-5400 3750);
FORCEPROP 2 LAST SIG_NAME RMII_PCH_SPRNGVLLE_ARB_IN
J 0
(-6500 3760);
DISPLAY 0.617021 (-6500 3760);
PAINT ORANGE (-6500 3760);
WIRE 16 -1 (-5400 3800)(-6550 3800);
FORCEPROP 2 LAST SIG_NAME RMII_PCH_SPRNGVLLE_ARB_OUT_R
J 0
(-6500 3810);
DISPLAY 0.617021 (-6500 3810);
PAINT ORANGE (-6500 3810);
WIRE 16 -1 (-6550 2400)(-5400 2400);
FORCEPROP 2 LAST SIG_NAME FM_PRSNT_2_1_N
J 0
(-6500 2410);
DISPLAY 0.617021 (-6500 2410);
PAINT ORANGE (-6500 2410);
WIRE 16 -1 (-5200 700)(-6000 700);
FORCEPROP 2 LAST SIG_NAME RMII_SPRNGVLLE_BMC_PCH_RXD1
J 0
(-5975 710);
DISPLAY 0.617021 (-5975 710);
PAINT ORANGE (-5975 710);
WIRE 16 -1 (-5000 700)(-4175 700);
FORCEPROP 2 LAST SIG_NAME RMII_SPRNGVLLE_BMC_PCH_RXD1_R1
J 0
(-4900 710);
DISPLAY 0.617021 (-4900 710);
PAINT ORANGE (-4900 710);
WIRE 16 -1 (-6000 1750)(-5400 1750);
FORCEPROP 2 LAST SIG_NAME TP_PCH_RSVD16
J 2
(-5645 1760);
DISPLAY 0.617021 (-5645 1760);
PAINT ORANGE (-5645 1760);
FORCEPROP 2 LASTPROP $XRERR UNIQUE?
J 0
(-6240 1750);
DISPLAY 0.638298 (-6240 1750);
PAINT MONO (-6240 1750);
DISPLAY INVISIBLE (-6240 1750);
WIRE 16 -1 (-6000 1025)(-5200 1025);
FORCEPROP 2 LAST SIG_NAME RMII_BMC_PCH_SPRNGVLLE_RXER
J 0
(-5975 1035);
DISPLAY 0.617021 (-5975 1035);
PAINT ORANGE (-5975 1035);
WIRE 16 -1 (-5000 1025)(-4175 1025);
FORCEPROP 2 LAST SIG_NAME RMII_BMC_PCH_SPRNGVLLE_RXER_R
J 0
(-4900 1035);
DISPLAY 0.617021 (-4900 1035);
PAINT ORANGE (-4900 1035);
WIRE 16 -1 (-5400 3850)(-6550 3850);
FORCEPROP 2 LAST SIG_NAME RST_PCIE_PCH_PERST_N
J 0
(-6500 3860);
DISPLAY 0.617021 (-6500 3860);
PAINT ORANGE (-6500 3860);
WIRE 16 -1 (-6000 1175)(-5200 1175);
FORCEPROP 2 LAST SIG_NAME RMII_PCH_SPRNGVLLE_ARB_OUT
J 0
(-5975 1185);
DISPLAY 0.617021 (-5975 1185);
PAINT ORANGE (-5975 1185);
WIRE 16 -1 (-5000 1175)(-4175 1175);
FORCEPROP 2 LAST SIG_NAME RMII_PCH_SPRNGVLLE_ARB_OUT_R
J 0
(-4900 1185);
DISPLAY 0.617021 (-4900 1185);
PAINT ORANGE (-4900 1185);
WIRE 16 -1 (-6550 2550)(-5400 2550);
FORCEPROP 2 LAST SIG_NAME FM_PRSNT_2_4_N
J 0
(-6500 2560);
DISPLAY 0.617021 (-6500 2560);
PAINT ORANGE (-6500 2560);
WIRE 16 -1 (-6000 1650)(-5400 1650);
FORCEPROP 2 LAST SIG_NAME TP_PCH_RSVD14
J 2
(-5645 1660);
DISPLAY 0.617021 (-5645 1660);
PAINT ORANGE (-5645 1660);
FORCEPROP 2 LASTPROP $XRERR UNIQUE?
J 0
(-6240 1650);
DISPLAY 0.638298 (-6240 1650);
PAINT MONO (-6240 1650);
DISPLAY INVISIBLE (-6240 1650);
WIRE 16 -1 (-6000 1600)(-5400 1600);
FORCEPROP 2 LAST SIG_NAME TP_PCH_RSVD13
J 2
(-5645 1610);
DISPLAY 0.617021 (-5645 1610);
PAINT ORANGE (-5645 1610);
FORCEPROP 2 LASTPROP $XRERR UNIQUE?
J 0
(-6240 1600);
DISPLAY 0.638298 (-6240 1600);
PAINT MONO (-6240 1600);
DISPLAY INVISIBLE (-6240 1600);
WIRE 16 -1 (-2025 3150)(-2700 3150);
FORCEPROP 2 LAST SIG_NAME SPI_PCH_MOSI_R
J 0
(-2465 3160);
DISPLAY 0.617021 (-2465 3160);
PAINT ORANGE (-2465 3160);
FORCEPROP 2 LASTPROP $XRERR UNIQUE?
J 0
(-2705 3160);
DISPLAY 0.638298 (-2705 3160);
PAINT MONO (-2705 3160);
DISPLAY INVISIBLE (-2705 3160);
WIRE 16 -1 (-2700 3300)(-1425 3300);
FORCEPROP 0 LAST SIG_NAME SPI_PCH_IO3
J 2
(-1425 3310);
DISPLAY 0.617021 (-1425 3310);
PAINT ORANGE (-1425 3310);
WIRE 16 -1 (-1425 3400)(-2700 3400);
FORCEPROP 0 LAST SIG_NAME SPI_PCH_TPM_CS_N
J 0
(-1785 3410);
DISPLAY 0.617021 (-1785 3410);
PAINT ORANGE (-1785 3410);
WIRE 16 -1 (-2100 2950)(-2700 2950);
FORCEPROP 2 LAST SIG_NAME TP_PCH_DISPA_BCLK
J 0
(-2465 2960);
DISPLAY 0.617021 (-2465 2960);
PAINT ORANGE (-2465 2960);
FORCEPROP 2 LASTPROP $XRERR UNIQUE?
J 0
(-2070 2950);
DISPLAY 0.638298 (-2070 2950);
PAINT MONO (-2070 2950);
DISPLAY INVISIBLE (-2070 2950);
WIRE 16 -1 (-675 1075)(-675 1175);
WIRE 16 -1 (-675 975)(-675 1075);
WIRE 16 -1 (-3050 1075)(-675 1075);
WIRE 16 -1 (-675 1175)(-1350 1175);
WIRE 16 -1 (-1350 1175)(-1850 1175);
WIRE 16 -1 (-1350 1175)(-1350 575);
WIRE 16 -1 (-3050 1175)(-3050 1075);
WIRE 16 -1 (-3050 1075)(-3050 975);
WIRE 16 -1 (-675 875)(-675 975);
WIRE 16 -1 (-3050 975)(-675 975);
WIRE 16 -1 (-3050 975)(-3050 875);
WIRE 16 -1 (-675 775)(-675 875);
WIRE 16 -1 (-3050 875)(-675 875);
WIRE 16 -1 (-2325 1175)(-3050 1175);
WIRE 16 -1 (-675 575)(-1350 575);
WIRE 16 -1 (-1350 575)(-1850 575);
WIRE 16 -1 (-1850 1175)(-1850 575);
WIRE 16 -1 (-1850 1175)(-2325 1175);
WIRE 16 -1 (-2325 1175)(-2325 575);
WIRE 16 -1 (-2325 575)(-1850 575);
WIRE 16 -1 (-675 675)(-675 575);
WIRE 16 -1 (-3050 875)(-3050 775);
WIRE 16 -1 (-675 675)(-675 775);
WIRE 16 -1 (-3050 775)(-675 775);
WIRE 16 -1 (-3050 775)(-3050 675);
WIRE 16 -1 (-3050 675)(-675 675);
WIRE 16 -1 (-3050 575)(-2325 575);
WIRE 16 -1 (-3050 675)(-3050 575);
WIRE 16 -1 (-2100 1800)(-2700 1800);
FORCEPROP 2 LAST SIG_NAME TP_PCH_RSVD4
J 0
(-2465 1810);
DISPLAY 0.617021 (-2465 1810);
PAINT ORANGE (-2465 1810);
FORCEPROP 2 LASTPROP $XRERR UNIQUE?
J 0
(-2070 1800);
DISPLAY 0.638298 (-2070 1800);
PAINT MONO (-2070 1800);
DISPLAY INVISIBLE (-2070 1800);
WIRE 16 -1 (-2700 3250)(-1425 3250);
FORCEPROP 0 LAST SIG_NAME SPI_PCH_IO2
J 2
(-1425 3260);
DISPLAY 0.617021 (-1425 3260);
PAINT ORANGE (-1425 3260);
WIRE 16 -1 (-2700 3700)(-1425 3700);
WIRE 16 -1 (-6550 2500)(-5400 2500);
FORCEPROP 2 LAST SIG_NAME FM_PRSNT_2_3_N
J 0
(-6500 2510);
DISPLAY 0.617021 (-6500 2510);
PAINT ORANGE (-6500 2510);
WIRE 16 -1 (-5400 2700)(-6550 2700);
FORCEPROP 2 LAST SIG_NAME FM_OCP_MEZZB_PRES_N
J 0
(-6500 2710);
DISPLAY 0.617021 (-6500 2710);
PAINT ORANGE (-6500 2710);
WIRE 16 -1 (-5400 2800)(-6000 2800);
FORCEPROP 2 LAST SIG_NAME TP_PCH_GPP_L10
J 0
(-5935 2810);
DISPLAY 0.617021 (-5935 2810);
PAINT ORANGE (-5935 2810);
FORCEPROP 2 LASTPROP $XRERR UNIQUE?
J 0
(-6240 2800);
DISPLAY 0.638298 (-6240 2800);
PAINT MONO (-6240 2800);
DISPLAY INVISIBLE (-6240 2800);
WIRE 16 -1 (-6000 1700)(-5400 1700);
FORCEPROP 2 LAST SIG_NAME TP_PCH_RSVD15
J 2
(-5645 1710);
DISPLAY 0.617021 (-5645 1710);
PAINT ORANGE (-5645 1710);
FORCEPROP 2 LASTPROP $XRERR UNIQUE?
J 0
(-6240 1700);
DISPLAY 0.638298 (-6240 1700);
PAINT MONO (-6240 1700);
DISPLAY INVISIBLE (-6240 1700);
WIRE 16 -1 (-6000 1800)(-5400 1800);
FORCEPROP 2 LAST SIG_NAME TP_PCH_RSVD17
J 2
(-5645 1810);
DISPLAY 0.617021 (-5645 1810);
PAINT ORANGE (-5645 1810);
FORCEPROP 2 LASTPROP $XRERR UNIQUE?
J 0
(-6240 1800);
DISPLAY 0.638298 (-6240 1800);
PAINT MONO (-6240 1800);
DISPLAY INVISIBLE (-6240 1800);
WIRE 16 -1 (-6000 1850)(-5400 1850);
FORCEPROP 2 LAST SIG_NAME TP_PCH_RSVD18
J 2
(-5645 1860);
DISPLAY 0.617021 (-5645 1860);
PAINT ORANGE (-5645 1860);
FORCEPROP 2 LASTPROP $XRERR UNIQUE?
J 0
(-6240 1850);
DISPLAY 0.638298 (-6240 1850);
PAINT MONO (-6240 1850);
DISPLAY INVISIBLE (-6240 1850);
WIRE 16 -1 (-6550 2650)(-5400 2650);
FORCEPROP 2 LAST SIG_NAME FM_PRSNT_2_6_N
J 0
(-6500 2660);
DISPLAY 0.617021 (-6500 2660);
PAINT ORANGE (-6500 2660);
WIRE 16 -1 (-6000 1900)(-5400 1900);
FORCEPROP 2 LAST SIG_NAME TP_PCH_RSVD19
J 2
(-5645 1910);
DISPLAY 0.617021 (-5645 1910);
PAINT ORANGE (-5645 1910);
FORCEPROP 2 LASTPROP $XRERR UNIQUE?
J 0
(-6240 1900);
DISPLAY 0.638298 (-6240 1900);
PAINT MONO (-6240 1900);
DISPLAY INVISIBLE (-6240 1900);
WIRE 16 -1 (-5400 2050)(-6000 2050);
FORCEPROP 2 LAST SIG_NAME TP_PCH_RSVD22
J 2
(-5645 2060);
DISPLAY 0.617021 (-5645 2060);
PAINT ORANGE (-5645 2060);
FORCEPROP 2 LASTPROP $XRERR UNIQUE?
J 0
(-6240 2050);
DISPLAY 0.638298 (-6240 2050);
PAINT MONO (-6240 2050);
DISPLAY INVISIBLE (-6240 2050);
WIRE 16 -1 (-6550 2450)(-5400 2450);
FORCEPROP 2 LAST SIG_NAME FM_PRSNT_2_2_N
J 0
(-6500 2460);
DISPLAY 0.617021 (-6500 2460);
PAINT ORANGE (-6500 2460);
WIRE 16 -1 (-5400 2850)(-6000 2850);
FORCEPROP 2 LAST SIG_NAME TP_PCH_GPP_L11
J 0
(-5935 2860);
DISPLAY 0.617021 (-5935 2860);
PAINT ORANGE (-5935 2860);
FORCEPROP 2 LASTPROP $XRERR UNIQUE?
J 0
(-6240 2850);
DISPLAY 0.638298 (-6240 2850);
PAINT MONO (-6240 2850);
DISPLAY INVISIBLE (-6240 2850);
WIRE 16 -1 (-6000 1950)(-5400 1950);
FORCEPROP 2 LAST SIG_NAME TP_PCH_RSVD20
J 2
(-5645 1960);
DISPLAY 0.617021 (-5645 1960);
PAINT ORANGE (-5645 1960);
FORCEPROP 2 LASTPROP $XRERR UNIQUE?
J 0
(-6240 1950);
DISPLAY 0.638298 (-6240 1950);
PAINT MONO (-6240 1950);
DISPLAY INVISIBLE (-6240 1950);
WIRE 16 -1 (-5400 2000)(-6000 2000);
FORCEPROP 2 LAST SIG_NAME TP_PCH_RSVD21
J 2
(-5645 2010);
DISPLAY 0.617021 (-5645 2010);
PAINT ORANGE (-5645 2010);
FORCEPROP 2 LASTPROP $XRERR UNIQUE?
J 0
(-6240 2000);
DISPLAY 0.638298 (-6240 2000);
PAINT MONO (-6240 2000);
DISPLAY INVISIBLE (-6240 2000);
WIRE 16 -1 (-5400 2100)(-6000 2100);
FORCEPROP 2 LAST SIG_NAME TP_PCH_RSVD23
J 2
(-5645 2110);
DISPLAY 0.617021 (-5645 2110);
PAINT ORANGE (-5645 2110);
FORCEPROP 2 LASTPROP $XRERR UNIQUE?
J 0
(-6240 2100);
DISPLAY 0.638298 (-6240 2100);
PAINT MONO (-6240 2100);
DISPLAY INVISIBLE (-6240 2100);
WIRE 16 -1 (-5400 2150)(-6000 2150);
FORCEPROP 2 LAST SIG_NAME TP_PCH_RSVD24
J 2
(-5645 2160);
DISPLAY 0.617021 (-5645 2160);
PAINT ORANGE (-5645 2160);
FORCEPROP 2 LASTPROP $XRERR UNIQUE?
J 0
(-6240 2150);
DISPLAY 0.638298 (-6240 2150);
PAINT MONO (-6240 2150);
DISPLAY INVISIBLE (-6240 2150);
WIRE 16 -1 (-5400 2200)(-6000 2200);
FORCEPROP 2 LAST SIG_NAME TP_PCH_RSVD25
J 2
(-5645 2210);
DISPLAY 0.617021 (-5645 2210);
PAINT ORANGE (-5645 2210);
FORCEPROP 2 LASTPROP $XRERR UNIQUE?
J 0
(-6240 2200);
DISPLAY 0.638298 (-6240 2200);
PAINT MONO (-6240 2200);
DISPLAY INVISIBLE (-6240 2200);
WIRE 16 -1 (-2100 1600)(-2700 1600);
FORCEPROP 2 LAST SIG_NAME TP_PCH_RSVD0
J 0
(-2465 1610);
DISPLAY 0.617021 (-2465 1610);
PAINT ORANGE (-2465 1610);
FORCEPROP 2 LASTPROP $XRERR UNIQUE?
J 0
(-2070 1600);
DISPLAY 0.638298 (-2070 1600);
PAINT MONO (-2070 1600);
DISPLAY INVISIBLE (-2070 1600);
WIRE 16 -1 (-2100 1650)(-2700 1650);
FORCEPROP 2 LAST SIG_NAME TP_PCH_RSVD1
J 0
(-2465 1660);
DISPLAY 0.617021 (-2465 1660);
PAINT ORANGE (-2465 1660);
FORCEPROP 2 LASTPROP $XRERR UNIQUE?
J 0
(-2070 1650);
DISPLAY 0.638298 (-2070 1650);
PAINT MONO (-2070 1650);
DISPLAY INVISIBLE (-2070 1650);
WIRE 16 -1 (-2100 1700)(-2700 1700);
FORCEPROP 2 LAST SIG_NAME TP_PCH_RSVD2
J 0
(-2465 1710);
DISPLAY 0.617021 (-2465 1710);
PAINT ORANGE (-2465 1710);
FORCEPROP 2 LASTPROP $XRERR UNIQUE?
J 0
(-2070 1700);
DISPLAY 0.638298 (-2070 1700);
PAINT MONO (-2070 1700);
DISPLAY INVISIBLE (-2070 1700);
WIRE 16 -1 (-2100 1750)(-2700 1750);
FORCEPROP 2 LAST SIG_NAME TP_PCH_RSVD3
J 0
(-2465 1760);
DISPLAY 0.617021 (-2465 1760);
PAINT ORANGE (-2465 1760);
FORCEPROP 2 LASTPROP $XRERR UNIQUE?
J 0
(-2070 1750);
DISPLAY 0.638298 (-2070 1750);
PAINT MONO (-2070 1750);
DISPLAY INVISIBLE (-2070 1750);
WIRE 16 -1 (-2100 1850)(-2700 1850);
FORCEPROP 2 LAST SIG_NAME TP_PCH_RSVD5
J 0
(-2465 1860);
DISPLAY 0.617021 (-2465 1860);
PAINT ORANGE (-2465 1860);
FORCEPROP 2 LASTPROP $XRERR UNIQUE?
J 0
(-2070 1850);
DISPLAY 0.638298 (-2070 1850);
PAINT MONO (-2070 1850);
DISPLAY INVISIBLE (-2070 1850);
WIRE 16 -1 (-2100 1900)(-2700 1900);
FORCEPROP 2 LAST SIG_NAME TP_PCH_RSVD6
J 0
(-2465 1910);
DISPLAY 0.617021 (-2465 1910);
PAINT ORANGE (-2465 1910);
FORCEPROP 2 LASTPROP $XRERR UNIQUE?
J 0
(-2070 1900);
DISPLAY 0.638298 (-2070 1900);
PAINT MONO (-2070 1900);
DISPLAY INVISIBLE (-2070 1900);
WIRE 16 -1 (-2100 1950)(-2700 1950);
FORCEPROP 2 LAST SIG_NAME TP_PCH_RSVD7
J 0
(-2465 1960);
DISPLAY 0.617021 (-2465 1960);
PAINT ORANGE (-2465 1960);
FORCEPROP 2 LASTPROP $XRERR UNIQUE?
J 0
(-2070 1950);
DISPLAY 0.638298 (-2070 1950);
PAINT MONO (-2070 1950);
DISPLAY INVISIBLE (-2070 1950);
WIRE 16 -1 (-2700 2000)(-2100 2000);
FORCEPROP 2 LAST SIG_NAME TP_PCH_RSVD8
J 0
(-2465 2010);
DISPLAY 0.617021 (-2465 2010);
PAINT ORANGE (-2465 2010);
FORCEPROP 2 LASTPROP $XRERR UNIQUE?
J 0
(-2070 2000);
DISPLAY 0.638298 (-2070 2000);
PAINT MONO (-2070 2000);
DISPLAY INVISIBLE (-2070 2000);
WIRE 16 -1 (-2700 2050)(-2100 2050);
FORCEPROP 2 LAST SIG_NAME TP_PCH_RSVD9
J 0
(-2465 2060);
DISPLAY 0.617021 (-2465 2060);
PAINT ORANGE (-2465 2060);
FORCEPROP 2 LASTPROP $XRERR UNIQUE?
J 0
(-2070 2050);
DISPLAY 0.638298 (-2070 2050);
PAINT MONO (-2070 2050);
DISPLAY INVISIBLE (-2070 2050);
WIRE 16 -1 (-2700 2200)(-2100 2200);
FORCEPROP 2 LAST SIG_NAME TP_PCH_RSVD12
J 0
(-2465 2210);
DISPLAY 0.617021 (-2465 2210);
PAINT ORANGE (-2465 2210);
FORCEPROP 2 LASTPROP $XRERR UNIQUE?
J 0
(-2070 2200);
DISPLAY 0.638298 (-2070 2200);
PAINT MONO (-2070 2200);
DISPLAY INVISIBLE (-2070 2200);
WIRE 16 -1 (-2700 3000)(-2100 3000);
FORCEPROP 2 LAST SIG_NAME TP_PCH_DISPA_SDI
J 0
(-2465 3010);
DISPLAY 0.617021 (-2465 3010);
PAINT ORANGE (-2465 3010);
FORCEPROP 2 LASTPROP $XRERR UNIQUE?
J 0
(-2070 3000);
DISPLAY 0.638298 (-2070 3000);
PAINT MONO (-2070 3000);
DISPLAY INVISIBLE (-2070 3000);
WIRE 16 -1 (-2700 3050)(-2100 3050);
FORCEPROP 2 LAST SIG_NAME TP_PCH_DISPA_SDO
J 0
(-2465 3060);
DISPLAY 0.617021 (-2465 3060);
PAINT ORANGE (-2465 3060);
FORCEPROP 2 LASTPROP $XRERR UNIQUE?
J 0
(-2070 3050);
DISPLAY 0.638298 (-2070 3050);
PAINT MONO (-2070 3050);
DISPLAY INVISIBLE (-2070 3050);
WIRE 16 -1 (-2700 2900)(-2100 2900);
FORCEPROP 2 LAST SIG_NAME TP_PCH_HDA_SYNC
J 0
(-2465 2910);
DISPLAY 0.617021 (-2465 2910);
PAINT ORANGE (-2465 2910);
FORCEPROP 2 LASTPROP $XRERR UNIQUE?
J 0
(-2070 2900);
DISPLAY 0.638298 (-2070 2900);
PAINT MONO (-2070 2900);
DISPLAY INVISIBLE (-2070 2900);
WIRE 16 -1 (-2100 2800)(-2700 2800);
FORCEPROP 2 LAST SIG_NAME TP_PCH_HDA_SDI_1
J 0
(-2465 2810);
DISPLAY 0.617021 (-2465 2810);
PAINT ORANGE (-2465 2810);
FORCEPROP 2 LASTPROP $XRERR UNIQUE?
J 0
(-2070 2800);
DISPLAY 0.638298 (-2070 2800);
PAINT MONO (-2070 2800);
DISPLAY INVISIBLE (-2070 2800);
WIRE 16 -1 (-2700 2750)(-2100 2750);
FORCEPROP 2 LAST SIG_NAME TP_PCH_HDA_SDI_0
J 0
(-2465 2760);
DISPLAY 0.617021 (-2465 2760);
PAINT ORANGE (-2465 2760);
FORCEPROP 2 LASTPROP $XRERR UNIQUE?
J 0
(-2070 2750);
DISPLAY 0.638298 (-2070 2750);
PAINT MONO (-2070 2750);
DISPLAY INVISIBLE (-2070 2750);
WIRE 16 -1 (-2700 2700)(-2100 2700);
FORCEPROP 2 LAST SIG_NAME TP_PCH_HSA_RST_N
J 0
(-2465 2710);
DISPLAY 0.617021 (-2465 2710);
PAINT ORANGE (-2465 2710);
FORCEPROP 2 LASTPROP $XRERR UNIQUE?
J 0
(-2070 2700);
DISPLAY 0.638298 (-2070 2700);
PAINT MONO (-2070 2700);
DISPLAY INVISIBLE (-2070 2700);
WIRE 16 -1 (-2100 2650)(-2700 2650);
FORCEPROP 2 LAST SIG_NAME TP_PCH_HDA_BCLK
J 0
(-2465 2660);
DISPLAY 0.617021 (-2465 2660);
PAINT ORANGE (-2465 2660);
FORCEPROP 2 LASTPROP $XRERR UNIQUE?
J 0
(-2070 2650);
DISPLAY 0.638298 (-2070 2650);
PAINT MONO (-2070 2650);
DISPLAY INVISIBLE (-2070 2650);
WIRE 16 -1 (-2700 3600)(-2100 3600);
FORCEPROP 0 LAST SIG_NAME TP_SPI_PCH_CS1_R1_N
J 0
(-2465 3610);
DISPLAY 0.617021 (-2465 3610);
PAINT ORANGE (-2465 3610);
FORCEPROP 2 LASTPROP $XRERR UNIQUE?
J 0
(-2070 3600);
DISPLAY 0.638298 (-2070 3600);
PAINT MONO (-2070 3600);
DISPLAY INVISIBLE (-2070 3600);
WIRE 16 -1 (-2050 3550)(-2700 3550);
FORCEPROP 2 LAST SIG_NAME SPI_PCH_CS0_R_N
J 0
(-2465 3560);
DISPLAY 0.617021 (-2465 3560);
PAINT ORANGE (-2465 3560);
FORCEPROP 2 LASTPROP $XRERR UNIQUE?
J 0
(-2705 3560);
DISPLAY 0.638298 (-2705 3560);
PAINT MONO (-2705 3560);
DISPLAY INVISIBLE (-2705 3560);
WIRE 16 -1 (-2700 3850)(-2100 3850);
FORCEPROP 2 LAST SIG_NAME TP_PCH_RSVD26
J 0
(-2465 3860);
DISPLAY 0.617021 (-2465 3860);
PAINT ORANGE (-2465 3860);
FORCEPROP 2 LASTPROP $XRERR UNIQUE?
J 0
(-2070 3850);
DISPLAY 0.638298 (-2070 3850);
PAINT MONO (-2070 3850);
DISPLAY INVISIBLE (-2070 3850);
WIRE 16 -1 (-2700 3900)(-2100 3900);
FORCEPROP 2 LAST SIG_NAME TP_PCH_RSVD27
J 0
(-2465 3910);
DISPLAY 0.617021 (-2465 3910);
PAINT ORANGE (-2465 3910);
FORCEPROP 2 LASTPROP $XRERR UNIQUE?
J 0
(-2070 3900);
DISPLAY 0.638298 (-2070 3900);
PAINT MONO (-2070 3900);
DISPLAY INVISIBLE (-2070 3900);
WIRE 16 -1 (-2700 3750)(-2100 3750);
FORCEPROP 2 LAST SIG_NAME TP_PCH_RSVD46
J 0
(-2465 3760);
DISPLAY 0.617021 (-2465 3760);
PAINT ORANGE (-2465 3760);
FORCEPROP 2 LASTPROP $XRERR UNIQUE?
J 0
(-2070 3750);
DISPLAY 0.638298 (-2070 3750);
PAINT MONO (-2070 3750);
DISPLAY INVISIBLE (-2070 3750);
WIRE 16 -1 (-2700 2550)(-1425 2550);
WIRE 16 -1 (-1425 3450)(-2700 3450);
FORCEPROP 2 LAST SIG_NAME SPI_PCH_CLK
J 2
(-1425 3460);
DISPLAY 0.617021 (-1425 3460);
PAINT ORANGE (-1425 3460);
WIRE 16 -1 (-2700 2850)(-1425 2850);
FORCEPROP 2 LAST SIG_NAME FM_FLASH_DESC_OVERRIDE
J 2
(-1435 2860);
DISPLAY 0.617021 (-1435 2860);
PAINT ORANGE (-1435 2860);
WIRE 16 -1 (-2700 2150)(-1425 2150);
FORCEPROP 2 LAST SIG_NAME FM_SINT_PRSNT_N
J 2
(-1435 2160);
DISPLAY 0.617021 (-1435 2160);
PAINT ORANGE (-1435 2160);
WIRE 16 -1 (-2700 2100)(-1425 2100);
FORCEPROP 2 LAST SIG_NAME FM_WBG_PRSNT_N
J 2
(-1435 2110);
DISPLAY 0.617021 (-1435 2110);
PAINT ORANGE (-1435 2110);
WIRE 16 -1 (-1425 3200)(-2700 3200);
FORCEPROP 0 LAST SIG_NAME SPI_PCH_MISO
J 2
(-1425 3210);
DISPLAY 0.617021 (-1425 3210);
PAINT ORANGE (-1425 3210);
WIRE 16 -1 (-2700 2500)(-1425 2500);
WIRE 16 -1 (-1425 3150)(-1825 3150);
FORCEPROP 2 LAST SIG_NAME SPI_PCH_MOSI
J 2
(-1425 3160);
DISPLAY 0.617021 (-1425 3160);
PAINT ORANGE (-1425 3160);
WIRE 16 -1 (-1425 3550)(-1850 3550);
FORCEPROP 2 LAST SIG_NAME SPI_PCH_CS0_N
J 2
(-1425 3560);
DISPLAY 0.617021 (-1425 3560);
PAINT ORANGE (-1425 3560);
DOT 1 (-3050 675);
DOT 1 (-3050 775);
DOT 1 (-3050 875);
DOT 1 (-3050 975);
DOT 1 (-2325 575);
DOT 1 (-3050 1075);
DOT 1 (-2325 1175);
DOT 1 (-1850 575);
DOT 1 (-1350 575);
DOT 1 (-1850 1175);
DOT 1 (-1350 1175);
DOT 1 (-675 675);
DOT 1 (-675 775);
DOT 1 (-675 875);
DOT 1 (-675 975);
DOT 1 (-675 1075);
FORCENOTE
INSTALLED WRONG DIRECTION
(-1300 600) 0;
DISPLAY LEFT (-1300 600);
DISPLAY 0.638298 (-1300 600);
PAINT PURPLE (-1300 600);
FORCENOTE
X
(-1625 600) 0;
DISPLAY LEFT (-1625 600);
DISPLAY 1.021277 (-1625 600);
PAINT PURPLE (-1625 600);
FORCENOTE
1
(-1625 700) 0;
DISPLAY LEFT (-1625 700);
DISPLAY 1.021277 (-1625 700);
PAINT PURPLE (-1625 700);
FORCENOTE
COMMENT
(-1225 1100) 0;
DISPLAY LEFT (-1225 1100);
DISPLAY 1.021277 (-1225 1100);
PAINT PURPLE (-1225 1100);
FORCENOTE
LBG
(-1125 700) 0;
DISPLAY LEFT (-1125 700);
DISPLAY 0.808511 (-1125 700);
PAINT PURPLE (-1125 700);
FORCENOTE
RSVD
(-1125 900) 0;
DISPLAY LEFT (-1125 900);
DISPLAY 0.808511 (-1125 900);
PAINT PURPLE (-1125 900);
FORCENOTE
WBG
(-1125 800) 0;
DISPLAY LEFT (-1125 800);
DISPLAY 0.808511 (-1125 800);
PAINT PURPLE (-1125 800);
FORCENOTE
PIN D8
(-1725 1100) 0;
DISPLAY LEFT (-1725 1100);
DISPLAY 1.021277 (-1725 1100);
PAINT PURPLE (-1725 1100);
FORCENOTE
WBG_PRSNT
(-1775 1000) 0;
DISPLAY LEFT (-1775 1000);
DISPLAY 1.021277 (-1775 1000);
PAINT PURPLE (-1775 1000);
FORCENOTE
1
(-1625 900) 0;
DISPLAY LEFT (-1625 900);
DISPLAY 1.021277 (-1625 900);
PAINT PURPLE (-1625 900);
FORCENOTE
0
(-1625 800) 0;
DISPLAY LEFT (-1625 800);
DISPLAY 1.021277 (-1625 800);
PAINT PURPLE (-1625 800);
FORCENOTE
SINT_PRSNT
(-2300 1000) 0;
DISPLAY LEFT (-2300 1000);
DISPLAY 1.021277 (-2300 1000);
PAINT PURPLE (-2300 1000);
FORCENOTE
PIN C18
(-2200 1100) 0;
DISPLAY LEFT (-2200 1100);
DISPLAY 1.021277 (-2200 1100);
PAINT PURPLE (-2200 1100);
FORCENOTE
PCH DETECTION
(-3025 1200) 0;
DISPLAY LEFT (-3025 1200);
DISPLAY 1.276596 (-3025 1200);
PAINT PURPLE (-3025 1200);
FORCENOTE
CGC_DUT_DETECT#
(-3000 1100) 0;
DISPLAY LEFT (-3000 1100);
DISPLAY 1.021277 (-3000 1100);
PAINT PURPLE (-3000 1100);
FORCENOTE
X
(-2100 600) 0;
DISPLAY LEFT (-2100 600);
DISPLAY 1.021277 (-2100 600);
PAINT PURPLE (-2100 600);
FORCENOTE
0
(-2100 900) 0;
DISPLAY LEFT (-2100 900);
DISPLAY 1.021277 (-2100 900);
PAINT PURPLE (-2100 900);
FORCENOTE
1
(-2100 800) 0;
DISPLAY LEFT (-2100 800);
DISPLAY 1.021277 (-2100 800);
PAINT PURPLE (-2100 800);
FORCENOTE
1
(-2100 700) 0;
DISPLAY LEFT (-2100 700);
DISPLAY 1.021277 (-2100 700);
PAINT PURPLE (-2100 700);
FORCENOTE
1
(-2725 600) 0;
DISPLAY LEFT (-2725 600);
DISPLAY 1.021277 (-2725 600);
PAINT PURPLE (-2725 600);
FORCENOTE
0
(-2725 800) 0;
DISPLAY LEFT (-2725 800);
DISPLAY 1.021277 (-2725 800);
PAINT PURPLE (-2725 800);
FORCENOTE
0
(-2725 900) 0;
DISPLAY LEFT (-2725 900);
DISPLAY 1.021277 (-2725 900);
PAINT PURPLE (-2725 900);
FORCENOTE
0
(-2725 700) 0;
DISPLAY LEFT (-2725 700);
DISPLAY 1.021277 (-2725 700);
PAINT PURPLE (-2725 700);
FORCENOTE
ROOM=SB
(-8200 375) 0;
DISPLAY LEFT (-8200 375);
DISPLAY 1.021277 (-8200 375);
PAINT PURPLE (-8200 375);
QUIT
